FILE_TYPE = MACRO_DRAWING;
SET COLOR_WIRE YELLOW;
SET COLOR_PROP MONO;
SET COLOR_DOT WHITE;
SET COLOR_ARC YELLOW;
SET COLOR_BODY GREEN;
SET COLOR_NOTE MONO;
SET PROP_DISPLAY VALUE;
SET PAGE_NUMBER P72;
FORCEADD PVDDQ_GHJ..1
(-7325 4250);
FORCEPROP 3 LASTPIN (-7325 4200) SIG_NAME PVDDQ_GHJ\g
J 0
(-7315 4210);
DISPLAY 0.659574 (-7315 4210);
PAINT MONO (-7315 4210);
DISPLAY INVISIBLE (-7315 4210);
FORCEPROP 1 LAST VOLTAGE 1.2V
J 0
(-7370 4207);
DISPLAY 0.340426 (-7370 4207);
PAINT SKYBLUE (-7370 4207);
DISPLAY INVISIBLE (-7370 4207);
FORCEPROP 2 LAST CDS_LIB mstr_symbols
J 0
(-7325 4250);
PAINT ORANGE (-7325 4250);
DISPLAY INVISIBLE (-7325 4250);
FORCEPROP 1 LAST BODY_TYPE PLUMBING
J 0
(-7370 4207);
DISPLAY 0.340426 (-7370 4207);
PAINT GREEN (-7370 4207);
DISPLAY INVISIBLE (-7370 4207);
FORCEPROP 1 LAST PATH I14
J 0
(-7275 4275);
DISPLAY 0.872340 (-7275 4275);
PAINT AQUA (-7275 4275);
DISPLAY INVISIBLE (-7275 4275);
FORCEPROP 1 LAST HDL_POWER PVDDQ_GHJ
J 1
(-7325 4300);
DISPLAY 0.872340 (-7325 4300);
PAINT GREEN (-7325 4300);
DISPLAY INVISIBLE (-7325 4300);
FORCEADD PVDDQ_KLM..1
(-5050 4250);
FORCEPROP 3 LASTPIN (-5050 4200) SIG_NAME PVDDQ_KLM\g
J 0
(-5040 4210);
DISPLAY 0.659574 (-5040 4210);
PAINT MONO (-5040 4210);
DISPLAY INVISIBLE (-5040 4210);
FORCEPROP 1 LAST VOLTAGE 1.2V
J 0
(-5095 4207);
DISPLAY 0.340426 (-5095 4207);
PAINT SKYBLUE (-5095 4207);
DISPLAY INVISIBLE (-5095 4207);
FORCEPROP 2 LAST CDS_LIB mstr_symbols
J 0
(-5050 4250);
PAINT ORANGE (-5050 4250);
DISPLAY INVISIBLE (-5050 4250);
FORCEPROP 1 LAST BODY_TYPE PLUMBING
J 0
(-5095 4207);
DISPLAY 0.340426 (-5095 4207);
PAINT GREEN (-5095 4207);
DISPLAY INVISIBLE (-5095 4207);
FORCEPROP 1 LAST PATH I15
J 0
(-5000 4275);
DISPLAY 0.872340 (-5000 4275);
PAINT AQUA (-5000 4275);
DISPLAY INVISIBLE (-5000 4275);
FORCEPROP 1 LAST HDL_POWER PVDDQ_KLM
J 1
(-5050 4300);
DISPLAY 0.872340 (-5050 4300);
PAINT GREEN (-5050 4300);
DISPLAY INVISIBLE (-5050 4300);
FORCEADD PVCCIO_CPU1..1
(-3850 4850);
FORCEPROP 3 LASTPIN (-3850 4800) SIG_NAME PVCCIO_CPU1\g
J 0
(-3840 4810);
DISPLAY 0.659574 (-3840 4810);
PAINT MONO (-3840 4810);
DISPLAY INVISIBLE (-3840 4810);
FORCEPROP 1 LAST VOLTAGE 1.1V
J 0
(-3895 4807);
DISPLAY 0.340426 (-3895 4807);
PAINT SKYBLUE (-3895 4807);
DISPLAY INVISIBLE (-3895 4807);
FORCEPROP 2 LAST CDS_LIB mstr_symbols
J 0
(-3850 4850);
PAINT ORANGE (-3850 4850);
DISPLAY INVISIBLE (-3850 4850);
FORCEPROP 1 LAST BODY_TYPE PLUMBING
J 0
(-3895 4807);
DISPLAY 0.340426 (-3895 4807);
PAINT GREEN (-3895 4807);
DISPLAY INVISIBLE (-3895 4807);
FORCEPROP 1 LAST PATH I17
J 0
(-3800 4875);
DISPLAY 0.872340 (-3800 4875);
PAINT AQUA (-3800 4875);
DISPLAY INVISIBLE (-3800 4875);
FORCEPROP 1 LAST HDL_POWER PVCCIO_CPU1
J 1
(-3850 4900);
DISPLAY 0.872340 (-3850 4900);
PAINT GREEN (-3850 4900);
DISPLAY INVISIBLE (-3850 4900);
FORCEADD PVCCIO_CPU1..1
(-1200 1050);
FORCEPROP 3 LASTPIN (-1200 1000) SIG_NAME PVCCIO_CPU1\g
J 0
(-1190 1010);
DISPLAY 0.659574 (-1190 1010);
PAINT MONO (-1190 1010);
DISPLAY INVISIBLE (-1190 1010);
FORCEPROP 1 LAST HDL_POWER PVCCIO_CPU1
J 1
(-1200 1100);
DISPLAY 0.872340 (-1200 1100);
PAINT GREEN (-1200 1100);
DISPLAY INVISIBLE (-1200 1100);
FORCEPROP 1 LAST PATH I18
J 0
(-1150 1075);
DISPLAY 0.872340 (-1150 1075);
PAINT AQUA (-1150 1075);
DISPLAY INVISIBLE (-1150 1075);
FORCEPROP 1 LAST BODY_TYPE PLUMBING
J 0
(-1245 1007);
DISPLAY 0.340426 (-1245 1007);
PAINT GREEN (-1245 1007);
DISPLAY INVISIBLE (-1245 1007);
FORCEPROP 2 LAST CDS_LIB mstr_symbols
J 0
(-1200 1050);
PAINT ORANGE (-1200 1050);
DISPLAY INVISIBLE (-1200 1050);
FORCEPROP 1 LAST VOLTAGE 1.1V
J 0
(-1245 1007);
DISPLAY 0.340426 (-1245 1007);
PAINT SKYBLUE (-1245 1007);
DISPLAY INVISIBLE (-1245 1007);
FORCEADD PVSA_CPU1..1
(-1600 4825);
FORCEPROP 3 LASTPIN (-1600 4775) SIG_NAME PVSA_CPU1\g
J 0
(-1590 4785);
DISPLAY 0.659574 (-1590 4785);
PAINT MONO (-1590 4785);
DISPLAY INVISIBLE (-1590 4785);
FORCEPROP 1 LAST VOLTAGE 1.1V
J 0
(-1645 4782);
DISPLAY 0.340426 (-1645 4782);
PAINT SKYBLUE (-1645 4782);
DISPLAY INVISIBLE (-1645 4782);
FORCEPROP 2 LAST CDS_LIB mstr_symbols
J 0
(-1600 4825);
PAINT ORANGE (-1600 4825);
DISPLAY INVISIBLE (-1600 4825);
FORCEPROP 1 LAST BODY_TYPE PLUMBING
J 0
(-1645 4782);
DISPLAY 0.340426 (-1645 4782);
PAINT GREEN (-1645 4782);
DISPLAY INVISIBLE (-1645 4782);
FORCEPROP 1 LAST PATH I22
J 0
(-1550 4850);
DISPLAY 0.872340 (-1550 4850);
PAINT AQUA (-1550 4850);
DISPLAY INVISIBLE (-1550 4850);
FORCEPROP 1 LAST HDL_POWER PVSA_CPU1
J 1
(-1600 4875);
DISPLAY 0.872340 (-1600 4875);
PAINT GREEN (-1600 4875);
DISPLAY INVISIBLE (-1600 4875);
FORCEADD GND..1
(-700 950);
FORCEPROP 3 LASTPIN (-700 1000) SIG_NAME GND\g
J 0
(-690 1010);
DISPLAY 0.659574 (-690 1010);
PAINT MONO (-690 1010);
DISPLAY INVISIBLE (-690 1010);
FORCEPROP 1 LAST VOLTAGE 0.0V
J 0
(-745 907);
DISPLAY 0.340426 (-745 907);
PAINT SKYBLUE (-745 907);
DISPLAY INVISIBLE (-745 907);
FORCEPROP 2 LAST CDS_LIB mstr_symbols
J 0
(-700 950);
PAINT ORANGE (-700 950);
DISPLAY INVISIBLE (-700 950);
FORCEPROP 1 LAST SIZE 1B
J 0
(-625 900);
DISPLAY 1.170213 (-625 900);
PAINT AQUA (-625 900);
DISPLAY INVISIBLE (-625 900);
FORCEPROP 1 LAST BODY_TYPE PLUMBING
J 0
(-745 907);
DISPLAY 0.340426 (-745 907);
PAINT GREEN (-745 907);
DISPLAY INVISIBLE (-745 907);
FORCEPROP 1 LAST PATH I23
J 0
(-625 950);
DISPLAY 0.872340 (-625 950);
PAINT AQUA (-625 950);
DISPLAY INVISIBLE (-625 950);
FORCEPROP 1 LAST HDL_POWER GND
J 0
(-700 1100);
DISPLAY 1.170213 (-700 1100);
PAINT GREEN (-700 1100);
DISPLAY INVISIBLE (-700 1100);
FORCEADD CAP..1
(-700 1175);
FORCEPROP 1 LAST LOCATION C3D3
J 0
(-650 1275);
DISPLAY 0.617021 (-650 1275);
PAINT AQUA (-650 1275);
FORCEPROP 1 LAST VALUE 10UF
J 0
(-650 1225);
DISPLAY 0.617021 (-650 1225);
PAINT SKYBLUE (-650 1225);
FORCEPROP 1 LAST VOLTAGE 4V
J 0
(-650 1175);
DISPLAY 0.617021 (-650 1175);
PAINT SKYBLUE (-650 1175);
FORCEPROP 1 LAST TOLERANCE 20%
J 0
(-650 1125);
DISPLAY 0.617021 (-650 1125);
PAINT SKYBLUE (-650 1125);
FORCEPROP 1 LASTPIN (-700 1275) $PN 1
J 0
(-690 1255);
DISPLAY 0.617021 (-690 1255);
PAINT GREEN (-690 1255);
FORCEPROP 1 LAST MATERIAL X6S
J 0
(-650 1075);
DISPLAY 0.617021 (-650 1075);
PAINT SKYBLUE (-650 1075);
FORCEPROP 1 LAST PART_NUMBER E15431-001
J 0
(-650 1025);
DISPLAY 0.617021 (-650 1025);
PAINT BLUE (-650 1025);
FORCEPROP 1 LASTPIN (-700 1075) $PN 2
J 0
(-690 1055);
DISPLAY 0.617021 (-690 1055);
PAINT GREEN (-690 1055);
FORCEPROP 1 LAST PACK_TYPE 0603LF
J 0
(-650 975);
DISPLAY 0.617021 (-650 975);
PAINT SKYBLUE (-650 975);
FORCEPROP 0 LAST GROUP PWR_MCP_CAP
J 0
(-660 926);
DISPLAY 0.638298 (-660 926);
PAINT BROWN (-660 926);
DISPLAY BOTH (-660 926);
FORCEPROP 2 LAST BOM_COST PROC_SOCKET
J 0
(-650 1375);
PAINT MONO (-650 1375);
DISPLAY INVISIBLE (-650 1375);
FORCEPROP 2 LAST CDS_LIB mstr_discrete
J 0
(-700 1175);
PAINT ORANGE (-700 1175);
DISPLAY INVISIBLE (-700 1175);
FORCEPROP 2 LAST CDS_SEC 1
J 0
(-650 1375);
DISPLAY 1.361702 (-650 1375);
PAINT ORANGE (-650 1375);
DISPLAY INVISIBLE (-650 1375);
FORCEPROP 2 LAST $SEC 1
J 0
(-650 1375);
DISPLAY 0.914894 (-650 1375);
PAINT MONO (-650 1375);
DISPLAY INVISIBLE (-650 1375);
FORCEPROP 2 LAST CDS_LOCATION C3D3
J 0
(-650 1275);
DISPLAY 0.617021 (-650 1275);
PAINT AQUA (-650 1275);
DISPLAY INVISIBLE (-650 1275);
FORCEPROP 1 LAST PATH I25
J 0
(-650 1325);
DISPLAY 0.978723 (-650 1325);
PAINT WHITE (-650 1325);
DISPLAY INVISIBLE (-650 1325);
FORCEPROP 2 LAST ROOM CPU1
J 0
(-650 1325);
PAINT MONO (-650 1325);
DISPLAY INVISIBLE (-650 1325);
FORCEADD VCC_CORE..1
(-1250 3300);
FORCEPROP 3 LASTPIN (-1250 3250) SIG_NAME PVCCMCP_CPU1\g
J 0
(-1240 3260);
DISPLAY 0.659574 (-1240 3260);
PAINT MONO (-1240 3260);
DISPLAY INVISIBLE (-1240 3260);
FORCEPROP 1 LAST HDL_POWER PVCCMCP_CPU1
J 1
(-1250 3350);
DISPLAY 0.617021 (-1250 3350);
PAINT GREEN (-1250 3350);
FORCEPROP 2 LAST CDS_LIB mstr_symbols
J 0
(-1250 3300);
PAINT ORANGE (-1250 3300);
DISPLAY INVISIBLE (-1250 3300);
FORCEPROP 1 LAST PATH I28
J 0
(-1200 3325);
DISPLAY 0.872340 (-1200 3325);
PAINT AQUA (-1200 3325);
DISPLAY INVISIBLE (-1200 3325);
FORCEADD VCC_CORE..1
(-1250 2575);
FORCEPROP 3 LASTPIN (-1250 2525) SIG_NAME PVCCIOMCP_CPU1\g
J 0
(-1240 2535);
DISPLAY 0.659574 (-1240 2535);
PAINT MONO (-1240 2535);
DISPLAY INVISIBLE (-1240 2535);
FORCEPROP 1 LAST HDL_POWER PVCCIOMCP_CPU1
J 1
(-1250 2625);
DISPLAY 0.617021 (-1250 2625);
PAINT GREEN (-1250 2625);
FORCEPROP 0 LAST VOLTAGE +0.95V
J 0
(-1250 2725);
DISPLAY 1.021277 (-1250 2725);
PAINT SKYBLUE (-1250 2725);
DISPLAY INVISIBLE (-1250 2725);
FORCEPROP 2 LAST CDS_LIB mstr_symbols
J 0
(-1250 2575);
PAINT ORANGE (-1250 2575);
DISPLAY INVISIBLE (-1250 2575);
FORCEPROP 1 LAST PATH I29
J 0
(-1200 2600);
DISPLAY 0.872340 (-1200 2600);
PAINT AQUA (-1200 2600);
DISPLAY INVISIBLE (-1200 2600);
FORCEADD SKX_EXT_B..20
(-6200 2550);
FORCEPROP 1 LAST LOCATION U2D1
J 0
(-7000 4100);
DISPLAY 0.617021 (-7000 4100);
PAINT AQUA (-7000 4100);
FORCEPROP 1 LAST PART_NUMBER TBD
J 0
(-7000 1050);
DISPLAY 0.617021 (-7000 1050);
PAINT BLUE (-7000 1050);
FORCEPROP 1 LAST MATERIAL IC
J 0
(-7000 4050);
DISPLAY 0.617021 (-7000 4050);
PAINT SKYBLUE (-7000 4050);
FORCEPROP 2 LASTPIN (-5350 3850) $PN EE44
J 0
(-5340 3860);
DISPLAY 0.617021 (-5340 3860);
PAINT ORANGE (-5340 3860);
FORCEPROP 2 LASTPIN (-5350 3800) $PN EF45
J 0
(-5340 3810);
DISPLAY 0.617021 (-5340 3810);
PAINT ORANGE (-5340 3810);
FORCEPROP 2 LASTPIN (-5350 3750) $PN DB53
J 0
(-5340 3760);
DISPLAY 0.617021 (-5340 3760);
PAINT ORANGE (-5340 3760);
FORCEPROP 2 LASTPIN (-5350 3700) $PN DB55
J 0
(-5340 3710);
DISPLAY 0.617021 (-5340 3710);
PAINT ORANGE (-5340 3710);
FORCEPROP 2 LASTPIN (-5350 3650) $PN DB57
J 0
(-5340 3660);
DISPLAY 0.617021 (-5340 3660);
PAINT ORANGE (-5340 3660);
FORCEPROP 2 LASTPIN (-5350 3600) $PN DB59
J 0
(-5340 3610);
DISPLAY 0.617021 (-5340 3610);
PAINT ORANGE (-5340 3610);
FORCEPROP 2 LASTPIN (-5350 3500) $PN DB63
J 0
(-5340 3510);
DISPLAY 0.617021 (-5340 3510);
PAINT ORANGE (-5340 3510);
FORCEPROP 2 LASTPIN (-5350 3450) $PN DD45
J 0
(-5340 3460);
DISPLAY 0.617021 (-5340 3460);
PAINT ORANGE (-5340 3460);
FORCEPROP 2 LASTPIN (-5350 3400) $PN DH45
J 0
(-5340 3410);
DISPLAY 0.617021 (-5340 3410);
PAINT ORANGE (-5340 3410);
FORCEPROP 2 LASTPIN (-5350 3350) $PN DH47
J 0
(-5340 3360);
DISPLAY 0.617021 (-5340 3360);
PAINT ORANGE (-5340 3360);
FORCEPROP 2 LASTPIN (-5350 3300) $PN DH49
J 0
(-5340 3310);
DISPLAY 0.617021 (-5340 3310);
PAINT ORANGE (-5340 3310);
FORCEPROP 2 LASTPIN (-5350 3250) $PN DH51
J 0
(-5340 3260);
DISPLAY 0.617021 (-5340 3260);
PAINT ORANGE (-5340 3260);
FORCEPROP 2 LASTPIN (-5350 3200) $PN DH53
J 0
(-5340 3210);
DISPLAY 0.617021 (-5340 3210);
PAINT ORANGE (-5340 3210);
FORCEPROP 2 LASTPIN (-5350 3150) $PN DH55
J 0
(-5340 3160);
DISPLAY 0.617021 (-5340 3160);
PAINT ORANGE (-5340 3160);
FORCEPROP 2 LASTPIN (-5350 3100) $PN DH57
J 0
(-5340 3110);
DISPLAY 0.617021 (-5340 3110);
PAINT ORANGE (-5340 3110);
FORCEPROP 2 LASTPIN (-5350 3050) $PN DH59
J 0
(-5340 3060);
DISPLAY 0.617021 (-5340 3060);
PAINT ORANGE (-5340 3060);
FORCEPROP 2 LASTPIN (-5350 3000) $PN DH61
J 0
(-5340 3010);
DISPLAY 0.617021 (-5340 3010);
PAINT ORANGE (-5340 3010);
FORCEPROP 2 LASTPIN (-5350 2950) $PN DH63
J 0
(-5340 2960);
DISPLAY 0.617021 (-5340 2960);
PAINT ORANGE (-5340 2960);
FORCEPROP 2 LASTPIN (-5350 2900) $PN DJ64
J 0
(-5340 2910);
DISPLAY 0.617021 (-5340 2910);
PAINT ORANGE (-5340 2910);
FORCEPROP 2 LASTPIN (-5350 2850) $PN DL46
J 0
(-5340 2860);
DISPLAY 0.617021 (-5340 2860);
PAINT ORANGE (-5340 2860);
FORCEPROP 2 LASTPIN (-5350 2800) $PN DL48
J 0
(-5340 2810);
DISPLAY 0.617021 (-5340 2810);
PAINT ORANGE (-5340 2810);
FORCEPROP 2 LASTPIN (-5350 2750) $PN DL50
J 0
(-5340 2760);
DISPLAY 0.617021 (-5340 2760);
PAINT ORANGE (-5340 2760);
FORCEPROP 2 LASTPIN (-5350 2700) $PN DL52
J 0
(-5340 2710);
DISPLAY 0.617021 (-5340 2710);
PAINT ORANGE (-5340 2710);
FORCEPROP 2 LASTPIN (-5350 2650) $PN DL54
J 0
(-5340 2660);
DISPLAY 0.617021 (-5340 2660);
PAINT ORANGE (-5340 2660);
FORCEPROP 2 LASTPIN (-5350 2600) $PN DL56
J 0
(-5340 2610);
DISPLAY 0.617021 (-5340 2610);
PAINT ORANGE (-5340 2610);
FORCEPROP 2 LASTPIN (-5350 2550) $PN DL58
J 0
(-5340 2560);
DISPLAY 0.617021 (-5340 2560);
PAINT ORANGE (-5340 2560);
FORCEPROP 2 LASTPIN (-5350 2500) $PN DL60
J 0
(-5340 2510);
DISPLAY 0.617021 (-5340 2510);
PAINT ORANGE (-5340 2510);
FORCEPROP 2 LASTPIN (-5350 2450) $PN DL62
J 0
(-5340 2460);
DISPLAY 0.617021 (-5340 2460);
PAINT ORANGE (-5340 2460);
FORCEPROP 2 LASTPIN (-5350 2400) $PN DU46
J 0
(-5340 2410);
DISPLAY 0.617021 (-5340 2410);
PAINT ORANGE (-5340 2410);
FORCEPROP 2 LASTPIN (-5350 2350) $PN DU48
J 0
(-5340 2360);
DISPLAY 0.617021 (-5340 2360);
PAINT ORANGE (-5340 2360);
FORCEPROP 2 LASTPIN (-5350 2300) $PN DU50
J 0
(-5340 2310);
DISPLAY 0.617021 (-5340 2310);
PAINT ORANGE (-5340 2310);
FORCEPROP 2 LASTPIN (-5350 2250) $PN DU52
J 0
(-5340 2260);
DISPLAY 0.617021 (-5340 2260);
PAINT ORANGE (-5340 2260);
FORCEPROP 2 LASTPIN (-5350 2200) $PN DU54
J 0
(-5340 2210);
DISPLAY 0.617021 (-5340 2210);
PAINT ORANGE (-5340 2210);
FORCEPROP 2 LASTPIN (-5350 2150) $PN DU56
J 0
(-5340 2160);
DISPLAY 0.617021 (-5340 2160);
PAINT ORANGE (-5340 2160);
FORCEPROP 2 LASTPIN (-5350 2100) $PN DU58
J 0
(-5340 2110);
DISPLAY 0.617021 (-5340 2110);
PAINT ORANGE (-5340 2110);
FORCEPROP 2 LASTPIN (-5350 2050) $PN DU60
J 0
(-5340 2060);
DISPLAY 0.617021 (-5340 2060);
PAINT ORANGE (-5340 2060);
FORCEPROP 2 LASTPIN (-5350 2000) $PN DU62
J 0
(-5340 2010);
DISPLAY 0.617021 (-5340 2010);
PAINT ORANGE (-5340 2010);
FORCEPROP 2 LASTPIN (-5350 1950) $PN DU64
J 0
(-5340 1960);
DISPLAY 0.617021 (-5340 1960);
PAINT ORANGE (-5340 1960);
FORCEPROP 2 LASTPIN (-5350 1900) $PN EC46
J 0
(-5340 1910);
DISPLAY 0.617021 (-5340 1910);
PAINT ORANGE (-5340 1910);
FORCEPROP 2 LASTPIN (-5350 1850) $PN EC48
J 0
(-5340 1860);
DISPLAY 0.617021 (-5340 1860);
PAINT ORANGE (-5340 1860);
FORCEPROP 2 LASTPIN (-5350 1800) $PN EC50
J 0
(-5340 1810);
DISPLAY 0.617021 (-5340 1810);
PAINT ORANGE (-5340 1810);
FORCEPROP 2 LASTPIN (-5350 1750) $PN EC52
J 0
(-5340 1760);
DISPLAY 0.617021 (-5340 1760);
PAINT ORANGE (-5340 1760);
FORCEPROP 2 LASTPIN (-5350 1700) $PN EC54
J 0
(-5340 1710);
DISPLAY 0.617021 (-5340 1710);
PAINT ORANGE (-5340 1710);
FORCEPROP 2 LASTPIN (-5350 1650) $PN EC56
J 0
(-5340 1660);
DISPLAY 0.617021 (-5340 1660);
PAINT ORANGE (-5340 1660);
FORCEPROP 2 LASTPIN (-5350 1600) $PN EC58
J 0
(-5340 1610);
DISPLAY 0.617021 (-5340 1610);
PAINT ORANGE (-5340 1610);
FORCEPROP 2 LASTPIN (-5350 1550) $PN EC60
J 0
(-5340 1560);
DISPLAY 0.617021 (-5340 1560);
PAINT ORANGE (-5340 1560);
FORCEPROP 2 LASTPIN (-5350 1500) $PN EC62
J 0
(-5340 1510);
DISPLAY 0.617021 (-5340 1510);
PAINT ORANGE (-5340 1510);
FORCEPROP 2 LASTPIN (-5350 1450) $PN EF49
J 0
(-5340 1460);
DISPLAY 0.617021 (-5340 1460);
PAINT ORANGE (-5340 1460);
FORCEPROP 2 LASTPIN (-5350 1350) $PN EF53
J 0
(-5340 1360);
DISPLAY 0.617021 (-5340 1360);
PAINT ORANGE (-5340 1360);
FORCEPROP 2 LASTPIN (-5350 1300) $PN EF59
J 0
(-5340 1310);
DISPLAY 0.617021 (-5340 1310);
PAINT ORANGE (-5340 1310);
FORCEPROP 2 LASTPIN (-7050 3850) $PN B47
J 2
(-7060 3860);
DISPLAY 0.617021 (-7060 3860);
PAINT ORANGE (-7060 3860);
FORCEPROP 2 LASTPIN (-7050 3800) $PN C46
J 2
(-7060 3810);
DISPLAY 0.617021 (-7060 3810);
PAINT ORANGE (-7060 3810);
FORCEPROP 2 LASTPIN (-7050 3750) $PN D45
J 2
(-7060 3760);
DISPLAY 0.617021 (-7060 3760);
PAINT ORANGE (-7060 3760);
FORCEPROP 2 LASTPIN (-7050 3700) $PN AF63
J 2
(-7060 3710);
DISPLAY 0.617021 (-7060 3710);
PAINT ORANGE (-7060 3710);
FORCEPROP 2 LASTPIN (-7050 3650) $PN AF61
J 2
(-7060 3660);
DISPLAY 0.617021 (-7060 3660);
PAINT ORANGE (-7060 3660);
FORCEPROP 2 LASTPIN (-7050 3600) $PN AF59
J 2
(-7060 3610);
DISPLAY 0.617021 (-7060 3610);
PAINT ORANGE (-7060 3610);
FORCEPROP 2 LASTPIN (-7050 3550) $PN AF57
J 2
(-7060 3560);
DISPLAY 0.617021 (-7060 3560);
PAINT ORANGE (-7060 3560);
FORCEPROP 2 LASTPIN (-7050 3500) $PN AF55
J 2
(-7060 3510);
DISPLAY 0.617021 (-7060 3510);
PAINT ORANGE (-7060 3510);
FORCEPROP 2 LASTPIN (-7050 3450) $PN AD45
J 2
(-7060 3460);
DISPLAY 0.617021 (-7060 3460);
PAINT ORANGE (-7060 3460);
FORCEPROP 2 LASTPIN (-7050 3400) $PN Y63
J 2
(-7060 3410);
DISPLAY 0.617021 (-7060 3410);
PAINT ORANGE (-7060 3410);
FORCEPROP 2 LASTPIN (-7050 3350) $PN Y61
J 2
(-7060 3360);
DISPLAY 0.617021 (-7060 3360);
PAINT ORANGE (-7060 3360);
FORCEPROP 2 LASTPIN (-7050 3300) $PN Y59
J 2
(-7060 3310);
DISPLAY 0.617021 (-7060 3310);
PAINT ORANGE (-7060 3310);
FORCEPROP 2 LASTPIN (-7050 3250) $PN Y57
J 2
(-7060 3260);
DISPLAY 0.617021 (-7060 3260);
PAINT ORANGE (-7060 3260);
FORCEPROP 2 LASTPIN (-7050 3200) $PN Y55
J 2
(-7060 3210);
DISPLAY 0.617021 (-7060 3210);
PAINT ORANGE (-7060 3210);
FORCEPROP 2 LASTPIN (-7050 3150) $PN Y53
J 2
(-7060 3160);
DISPLAY 0.617021 (-7060 3160);
PAINT ORANGE (-7060 3160);
FORCEPROP 2 LASTPIN (-7050 3100) $PN Y51
J 2
(-7060 3110);
DISPLAY 0.617021 (-7060 3110);
PAINT ORANGE (-7060 3110);
FORCEPROP 2 LASTPIN (-7050 3050) $PN Y49
J 2
(-7060 3060);
DISPLAY 0.617021 (-7060 3060);
PAINT ORANGE (-7060 3060);
FORCEPROP 2 LASTPIN (-7050 3000) $PN Y47
J 2
(-7060 3010);
DISPLAY 0.617021 (-7060 3010);
PAINT ORANGE (-7060 3010);
FORCEPROP 2 LASTPIN (-7050 2950) $PN Y45
J 2
(-7060 2960);
DISPLAY 0.617021 (-7060 2960);
PAINT ORANGE (-7060 2960);
FORCEPROP 2 LASTPIN (-7050 2900) $PN W64
J 2
(-7060 2910);
DISPLAY 0.617021 (-7060 2910);
PAINT ORANGE (-7060 2910);
FORCEPROP 2 LASTPIN (-7050 2850) $PN U62
J 2
(-7060 2860);
DISPLAY 0.617021 (-7060 2860);
PAINT ORANGE (-7060 2860);
FORCEPROP 2 LASTPIN (-7050 2800) $PN U60
J 2
(-7060 2810);
DISPLAY 0.617021 (-7060 2810);
PAINT ORANGE (-7060 2810);
FORCEPROP 2 LASTPIN (-7050 2750) $PN U58
J 2
(-7060 2760);
DISPLAY 0.617021 (-7060 2760);
PAINT ORANGE (-7060 2760);
FORCEPROP 2 LASTPIN (-7050 2700) $PN U56
J 2
(-7060 2710);
DISPLAY 0.617021 (-7060 2710);
PAINT ORANGE (-7060 2710);
FORCEPROP 2 LASTPIN (-7050 2650) $PN U54
J 2
(-7060 2660);
DISPLAY 0.617021 (-7060 2660);
PAINT ORANGE (-7060 2660);
FORCEPROP 2 LASTPIN (-7050 2600) $PN U52
J 2
(-7060 2610);
DISPLAY 0.617021 (-7060 2610);
PAINT ORANGE (-7060 2610);
FORCEPROP 2 LASTPIN (-7050 2550) $PN U50
J 2
(-7060 2560);
DISPLAY 0.617021 (-7060 2560);
PAINT ORANGE (-7060 2560);
FORCEPROP 2 LASTPIN (-7050 2500) $PN U48
J 2
(-7060 2510);
DISPLAY 0.617021 (-7060 2510);
PAINT ORANGE (-7060 2510);
FORCEPROP 2 LASTPIN (-7050 2450) $PN U46
J 2
(-7060 2460);
DISPLAY 0.617021 (-7060 2460);
PAINT ORANGE (-7060 2460);
FORCEPROP 2 LASTPIN (-7050 2400) $PN N64
J 2
(-7060 2410);
DISPLAY 0.617021 (-7060 2410);
PAINT ORANGE (-7060 2410);
FORCEPROP 2 LASTPIN (-7050 2350) $PN L62
J 2
(-7060 2360);
DISPLAY 0.617021 (-7060 2360);
PAINT ORANGE (-7060 2360);
FORCEPROP 2 LASTPIN (-7050 2300) $PN L60
J 2
(-7060 2310);
DISPLAY 0.617021 (-7060 2310);
PAINT ORANGE (-7060 2310);
FORCEPROP 2 LASTPIN (-7050 2250) $PN L58
J 2
(-7060 2260);
DISPLAY 0.617021 (-7060 2260);
PAINT ORANGE (-7060 2260);
FORCEPROP 2 LASTPIN (-7050 2200) $PN L56
J 2
(-7060 2210);
DISPLAY 0.617021 (-7060 2210);
PAINT ORANGE (-7060 2210);
FORCEPROP 2 LASTPIN (-7050 2150) $PN L54
J 2
(-7060 2160);
DISPLAY 0.617021 (-7060 2160);
PAINT ORANGE (-7060 2160);
FORCEPROP 2 LASTPIN (-7050 2100) $PN L52
J 2
(-7060 2110);
DISPLAY 0.617021 (-7060 2110);
PAINT ORANGE (-7060 2110);
FORCEPROP 2 LASTPIN (-7050 2050) $PN L50
J 2
(-7060 2060);
DISPLAY 0.617021 (-7060 2060);
PAINT ORANGE (-7060 2060);
FORCEPROP 2 LASTPIN (-7050 2000) $PN L48
J 2
(-7060 2010);
DISPLAY 0.617021 (-7060 2010);
PAINT ORANGE (-7060 2010);
FORCEPROP 2 LASTPIN (-7050 1950) $PN L46
J 2
(-7060 1960);
DISPLAY 0.617021 (-7060 1960);
PAINT ORANGE (-7060 1960);
FORCEPROP 2 LASTPIN (-7050 1900) $PN E64
J 2
(-7060 1910);
DISPLAY 0.617021 (-7060 1910);
PAINT ORANGE (-7060 1910);
FORCEPROP 2 LASTPIN (-7050 1850) $PN E62
J 2
(-7060 1860);
DISPLAY 0.617021 (-7060 1860);
PAINT ORANGE (-7060 1860);
FORCEPROP 2 LASTPIN (-7050 1800) $PN E60
J 2
(-7060 1810);
DISPLAY 0.617021 (-7060 1810);
PAINT ORANGE (-7060 1810);
FORCEPROP 2 LASTPIN (-7050 1750) $PN E58
J 2
(-7060 1760);
DISPLAY 0.617021 (-7060 1760);
PAINT ORANGE (-7060 1760);
FORCEPROP 2 LASTPIN (-7050 1700) $PN E56
J 2
(-7060 1710);
DISPLAY 0.617021 (-7060 1710);
PAINT ORANGE (-7060 1710);
FORCEPROP 2 LASTPIN (-7050 1650) $PN E54
J 2
(-7060 1660);
DISPLAY 0.617021 (-7060 1660);
PAINT ORANGE (-7060 1660);
FORCEPROP 2 LASTPIN (-7050 1600) $PN E52
J 2
(-7060 1610);
DISPLAY 0.617021 (-7060 1610);
PAINT ORANGE (-7060 1610);
FORCEPROP 2 LASTPIN (-7050 1550) $PN E50
J 2
(-7060 1560);
DISPLAY 0.617021 (-7060 1560);
PAINT ORANGE (-7060 1560);
FORCEPROP 2 LASTPIN (-7050 1500) $PN E48
J 2
(-7060 1510);
DISPLAY 0.617021 (-7060 1510);
PAINT ORANGE (-7060 1510);
FORCEPROP 2 LASTPIN (-7050 1450) $PN E46
J 2
(-7060 1460);
DISPLAY 0.617021 (-7060 1460);
PAINT ORANGE (-7060 1460);
FORCEPROP 2 LASTPIN (-7050 1350) $PN B59
J 2
(-7060 1360);
DISPLAY 0.617021 (-7060 1360);
PAINT ORANGE (-7060 1360);
FORCEPROP 2 LASTPIN (-7050 1300) $PN B53
J 2
(-7060 1310);
DISPLAY 0.617021 (-7060 1310);
PAINT ORANGE (-7060 1310);
FORCEPROP 2 LASTPIN (-7050 1250) $PN B49
J 2
(-7060 1260);
DISPLAY 0.617021 (-7060 1260);
PAINT ORANGE (-7060 1260);
FORCEPROP 2 LASTPIN (-5350 3550) $PN DB61
J 0
(-5340 3560);
DISPLAY 0.617021 (-5340 3560);
PAINT ORANGE (-5340 3560);
FORCEPROP 1 LAST PACK_TYPE BGA1
J 0
(-7000 4150);
PAINT SKYBLUE (-7000 4150);
DISPLAY INVISIBLE (-7000 4150);
FORCEPROP 2 LAST SEC_TYPE BGA1
J 0
(-7000 4150);
DISPLAY 1.021277 (-7000 4150);
PAINT ORANGE (-7000 4150);
DISPLAY INVISIBLE (-7000 4150);
FORCEPROP 2 LAST CDS_LIB chpset_lib
J 0
(-6200 2550);
PAINT ORANGE (-6200 2550);
DISPLAY INVISIBLE (-6200 2550);
FORCEPROP 2 LAST SEC 20
J 0
(-7000 4150);
DISPLAY 0.680851 (-7000 4150);
PAINT MONO (-7000 4150);
DISPLAY INVISIBLE (-7000 4150);
FORCEPROP 2 LAST CDS_LOCATION U2D1
J 0
(-7000 4100);
DISPLAY 0.617021 (-7000 4100);
PAINT AQUA (-7000 4100);
DISPLAY INVISIBLE (-7000 4100);
FORCEPROP 1 LAST PATH I32
J 0
(-6200 4050);
PAINT GREEN (-6200 4050);
DISPLAY INVISIBLE (-6200 4050);
FORCEADD SKX_EXT_B..21
(-2700 2575);
FORCEPROP 1 LAST LOCATION U2D1
J 0
(-3550 4825);
DISPLAY 0.617021 (-3550 4825);
PAINT AQUA (-3550 4825);
FORCEPROP 1 LAST PART_NUMBER TBD
J 0
(-3550 325);
DISPLAY 0.617021 (-3550 325);
PAINT BLUE (-3550 325);
FORCEPROP 1 LAST MATERIAL IC
J 0
(-3550 4775);
DISPLAY 0.617021 (-3550 4775);
PAINT SKYBLUE (-3550 4775);
FORCEPROP 2 LASTPIN (-1800 4575) $PN CB65
J 0
(-1790 4585);
DISPLAY 0.617021 (-1790 4585);
PAINT ORANGE (-1790 4585);
FORCEPROP 2 LASTPIN (-1800 4525) $PN CB67
J 0
(-1790 4535);
DISPLAY 0.617021 (-1790 4535);
PAINT ORANGE (-1790 4535);
FORCEPROP 2 LASTPIN (-1800 4475) $PN CB69
J 0
(-1790 4485);
DISPLAY 0.617021 (-1790 4485);
PAINT ORANGE (-1790 4485);
FORCEPROP 2 LASTPIN (-1800 4425) $PN CC66
J 0
(-1790 4435);
DISPLAY 0.617021 (-1790 4435);
PAINT ORANGE (-1790 4435);
FORCEPROP 2 LASTPIN (-1800 4375) $PN CC68
J 0
(-1790 4385);
DISPLAY 0.617021 (-1790 4385);
PAINT ORANGE (-1790 4385);
FORCEPROP 2 LASTPIN (-1800 4325) $PN CC70
J 0
(-1790 4335);
DISPLAY 0.617021 (-1790 4335);
PAINT ORANGE (-1790 4335);
FORCEPROP 2 LASTPIN (-1800 4275) $PN CD65
J 0
(-1790 4285);
DISPLAY 0.617021 (-1790 4285);
PAINT ORANGE (-1790 4285);
FORCEPROP 2 LASTPIN (-1800 4225) $PN CD67
J 0
(-1790 4235);
DISPLAY 0.617021 (-1790 4235);
PAINT ORANGE (-1790 4235);
FORCEPROP 2 LASTPIN (-1800 4175) $PN CD69
J 0
(-1790 4185);
DISPLAY 0.617021 (-1790 4185);
PAINT ORANGE (-1790 4185);
FORCEPROP 2 LASTPIN (-1800 4125) $PN CD71
J 0
(-1790 4135);
DISPLAY 0.617021 (-1790 4135);
PAINT ORANGE (-1790 4135);
FORCEPROP 2 LASTPIN (-1800 4075) $PN CE64
J 0
(-1790 4085);
DISPLAY 0.617021 (-1790 4085);
PAINT ORANGE (-1790 4085);
FORCEPROP 2 LASTPIN (-1800 4025) $PN CE66
J 0
(-1790 4035);
DISPLAY 0.617021 (-1790 4035);
PAINT ORANGE (-1790 4035);
FORCEPROP 2 LASTPIN (-1800 3975) $PN CE68
J 0
(-1790 3985);
DISPLAY 0.617021 (-1790 3985);
PAINT ORANGE (-1790 3985);
FORCEPROP 2 LASTPIN (-1800 3925) $PN CE72
J 0
(-1790 3935);
DISPLAY 0.617021 (-1790 3935);
PAINT ORANGE (-1790 3935);
FORCEPROP 2 LASTPIN (-1800 3875) $PN CE74
J 0
(-1790 3885);
DISPLAY 0.617021 (-1790 3885);
PAINT ORANGE (-1790 3885);
FORCEPROP 2 LASTPIN (-1800 3825) $PN CF65
J 0
(-1790 3835);
DISPLAY 0.617021 (-1790 3835);
PAINT ORANGE (-1790 3835);
FORCEPROP 2 LASTPIN (-1800 3775) $PN CF67
J 0
(-1790 3785);
DISPLAY 0.617021 (-1790 3785);
PAINT ORANGE (-1790 3785);
FORCEPROP 2 LASTPIN (-1800 3725) $PN CF73
J 0
(-1790 3735);
DISPLAY 0.617021 (-1790 3735);
PAINT ORANGE (-1790 3735);
FORCEPROP 2 LASTPIN (-1800 3675) $PN CF75
J 0
(-1790 3685);
DISPLAY 0.617021 (-1790 3685);
PAINT ORANGE (-1790 3685);
FORCEPROP 2 LASTPIN (-1800 3625) $PN CG64
J 0
(-1790 3635);
DISPLAY 0.617021 (-1790 3635);
PAINT ORANGE (-1790 3635);
FORCEPROP 2 LASTPIN (-1800 3575) $PN CG66
J 0
(-1790 3585);
DISPLAY 0.617021 (-1790 3585);
PAINT ORANGE (-1790 3585);
FORCEPROP 2 LASTPIN (-1800 3525) $PN CG74
J 0
(-1790 3535);
DISPLAY 0.617021 (-1790 3535);
PAINT ORANGE (-1790 3535);
FORCEPROP 2 LASTPIN (-1800 3475) $PN CH65
J 0
(-1790 3485);
DISPLAY 0.617021 (-1790 3485);
PAINT ORANGE (-1790 3485);
FORCEPROP 2 LASTPIN (-1800 3425) $PN CH75
J 0
(-1790 3435);
DISPLAY 0.617021 (-1790 3435);
PAINT ORANGE (-1790 3435);
FORCEPROP 2 LASTPIN (-1800 3375) $PN CJ64
J 0
(-1790 3385);
DISPLAY 0.617021 (-1790 3385);
PAINT ORANGE (-1790 3385);
FORCEPROP 2 LASTPIN (-1800 3325) $PN CJ66
J 0
(-1790 3335);
DISPLAY 0.617021 (-1790 3335);
PAINT ORANGE (-1790 3335);
FORCEPROP 2 LASTPIN (-3600 4575) $PN AR28
J 2
(-3610 4585);
DISPLAY 0.617021 (-3610 4585);
PAINT ORANGE (-3610 4585);
FORCEPROP 2 LASTPIN (-3600 4525) $PN AL28
J 2
(-3610 4535);
DISPLAY 0.617021 (-3610 4535);
PAINT ORANGE (-3610 4535);
FORCEPROP 2 LASTPIN (-3600 4475) $PN AM29
J 2
(-3610 4485);
DISPLAY 0.617021 (-3610 4485);
PAINT ORANGE (-3610 4485);
FORCEPROP 2 LASTPIN (-3600 4425) $PN AG34
J 2
(-3610 4435);
DISPLAY 0.617021 (-3610 4435);
PAINT ORANGE (-3610 4435);
FORCEPROP 2 LASTPIN (-3600 4375) $PN AE34
J 2
(-3610 4385);
DISPLAY 0.617021 (-3610 4385);
PAINT ORANGE (-3610 4385);
FORCEPROP 2 LASTPIN (-3600 4325) $PN AD35
J 2
(-3610 4335);
DISPLAY 0.617021 (-3610 4335);
PAINT ORANGE (-3610 4335);
FORCEPROP 2 LASTPIN (-3600 4275) $PN AF35
J 2
(-3610 4285);
DISPLAY 0.617021 (-3610 4285);
PAINT ORANGE (-3610 4285);
FORCEPROP 2 LASTPIN (-3600 4225) $PN AC36
J 2
(-3610 4235);
DISPLAY 0.617021 (-3610 4235);
PAINT ORANGE (-3610 4235);
FORCEPROP 2 LASTPIN (-3600 4175) $PN AD37
J 2
(-3610 4185);
DISPLAY 0.617021 (-3610 4185);
PAINT ORANGE (-3610 4185);
FORCEPROP 2 LASTPIN (-3600 4125) $PN AE36
J 2
(-3610 4135);
DISPLAY 0.617021 (-3610 4135);
PAINT ORANGE (-3610 4135);
FORCEPROP 2 LASTPIN (-3600 4075) $PN BF27
J 2
(-3610 4085);
DISPLAY 0.617021 (-3610 4085);
PAINT ORANGE (-3610 4085);
FORCEPROP 2 LASTPIN (-3600 4025) $PN BG26
J 2
(-3610 4035);
DISPLAY 0.617021 (-3610 4035);
PAINT ORANGE (-3610 4035);
FORCEPROP 2 LASTPIN (-3600 3975) $PN BH25
J 2
(-3610 3985);
DISPLAY 0.617021 (-3610 3985);
PAINT ORANGE (-3610 3985);
FORCEPROP 2 LASTPIN (-3600 3925) $PN BH27
J 2
(-3610 3935);
DISPLAY 0.617021 (-3610 3935);
PAINT ORANGE (-3610 3935);
FORCEPROP 2 LASTPIN (-3600 3875) $PN BJ26
J 2
(-3610 3885);
DISPLAY 0.617021 (-3610 3885);
PAINT ORANGE (-3610 3885);
FORCEPROP 2 LASTPIN (-3600 3825) $PN BK25
J 2
(-3610 3835);
DISPLAY 0.617021 (-3610 3835);
PAINT ORANGE (-3610 3835);
FORCEPROP 2 LASTPIN (-3600 3775) $PN BK27
J 2
(-3610 3785);
DISPLAY 0.617021 (-3610 3785);
PAINT ORANGE (-3610 3785);
FORCEPROP 2 LASTPIN (-3600 3725) $PN BL26
J 2
(-3610 3735);
DISPLAY 0.617021 (-3610 3735);
PAINT ORANGE (-3610 3735);
FORCEPROP 2 LASTPIN (-3600 3675) $PN BM27
J 2
(-3610 3685);
DISPLAY 0.617021 (-3610 3685);
PAINT ORANGE (-3610 3685);
FORCEPROP 2 LASTPIN (-3600 3625) $PN CH27
J 2
(-3610 3635);
DISPLAY 0.617021 (-3610 3635);
PAINT ORANGE (-3610 3635);
FORCEPROP 2 LASTPIN (-3600 3575) $PN CJ28
J 2
(-3610 3585);
DISPLAY 0.617021 (-3610 3585);
PAINT ORANGE (-3610 3585);
FORCEPROP 2 LASTPIN (-3600 3525) $PN CC26
J 2
(-3610 3535);
DISPLAY 0.617021 (-3610 3535);
PAINT ORANGE (-3610 3535);
FORCEPROP 2 LASTPIN (-3600 3475) $PN CD27
J 2
(-3610 3485);
DISPLAY 0.617021 (-3610 3485);
PAINT ORANGE (-3610 3485);
FORCEPROP 2 LASTPIN (-3600 3425) $PN CF27
J 2
(-3610 3435);
DISPLAY 0.617021 (-3610 3435);
PAINT ORANGE (-3610 3435);
FORCEPROP 2 LASTPIN (-3600 3375) $PN AV27
J 2
(-3610 3385);
DISPLAY 0.617021 (-3610 3385);
PAINT ORANGE (-3610 3385);
FORCEPROP 2 LASTPIN (-3600 3325) $PN AW26
J 2
(-3610 3335);
DISPLAY 0.617021 (-3610 3335);
PAINT ORANGE (-3610 3335);
FORCEPROP 2 LASTPIN (-3600 3275) $PN AY27
J 2
(-3610 3285);
DISPLAY 0.617021 (-3610 3285);
PAINT ORANGE (-3610 3285);
FORCEPROP 2 LASTPIN (-3600 3225) $PN BA26
J 2
(-3610 3235);
DISPLAY 0.617021 (-3610 3235);
PAINT ORANGE (-3610 3235);
FORCEPROP 2 LASTPIN (-3600 3175) $PN BB27
J 2
(-3610 3185);
DISPLAY 0.617021 (-3610 3185);
PAINT ORANGE (-3610 3185);
FORCEPROP 2 LASTPIN (-3600 3125) $PN BC26
J 2
(-3610 3135);
DISPLAY 0.617021 (-3610 3135);
PAINT ORANGE (-3610 3135);
FORCEPROP 2 LASTPIN (-3600 3075) $PN W10
J 2
(-3610 3085);
DISPLAY 0.617021 (-3610 3085);
PAINT ORANGE (-3610 3085);
FORCEPROP 2 LASTPIN (-3600 3025) $PN N18
J 2
(-3610 3035);
DISPLAY 0.617021 (-3610 3035);
PAINT ORANGE (-3610 3035);
FORCEPROP 2 LASTPIN (-3600 2975) $PN M9
J 2
(-3610 2985);
DISPLAY 0.617021 (-3610 2985);
PAINT ORANGE (-3610 2985);
FORCEPROP 2 LASTPIN (-3600 2925) $PN M7
J 2
(-3610 2935);
DISPLAY 0.617021 (-3610 2935);
PAINT ORANGE (-3610 2935);
FORCEPROP 2 LASTPIN (-3600 2875) $PN K15
J 2
(-3610 2885);
DISPLAY 0.617021 (-3610 2885);
PAINT ORANGE (-3610 2885);
FORCEPROP 2 LASTPIN (-3600 2825) $PN J2
J 2
(-3610 2835);
DISPLAY 0.617021 (-3610 2835);
PAINT ORANGE (-3610 2835);
FORCEPROP 2 LASTPIN (-3600 2775) $PN EB15
J 2
(-3610 2785);
DISPLAY 0.617021 (-3610 2785);
PAINT ORANGE (-3610 2785);
FORCEPROP 2 LASTPIN (-3600 2725) $PN EA12
J 2
(-3610 2735);
DISPLAY 0.617021 (-3610 2735);
PAINT ORANGE (-3610 2735);
FORCEPROP 2 LASTPIN (-3600 2675) $PN DU20
J 2
(-3610 2685);
DISPLAY 0.617021 (-3610 2685);
PAINT ORANGE (-3610 2685);
FORCEPROP 2 LASTPIN (-3600 2625) $PN DR2
J 2
(-3610 2635);
DISPLAY 0.617021 (-3610 2635);
PAINT ORANGE (-3610 2635);
FORCEPROP 2 LASTPIN (-3600 2575) $PN DR10
J 2
(-3610 2585);
DISPLAY 0.617021 (-3610 2585);
PAINT ORANGE (-3610 2585);
FORCEPROP 2 LASTPIN (-3600 2525) $PN DP19
J 2
(-3610 2535);
DISPLAY 0.617021 (-3610 2535);
PAINT ORANGE (-3610 2535);
FORCEPROP 2 LASTPIN (-3600 2475) $PN DN8
J 2
(-3610 2485);
DISPLAY 0.617021 (-3610 2485);
PAINT ORANGE (-3610 2485);
FORCEPROP 2 LASTPIN (-3600 2425) $PN DM17
J 2
(-3610 2435);
DISPLAY 0.617021 (-3610 2435);
PAINT ORANGE (-3610 2435);
FORCEPROP 2 LASTPIN (-3600 2375) $PN DJ16
J 2
(-3610 2385);
DISPLAY 0.617021 (-3610 2385);
PAINT ORANGE (-3610 2385);
FORCEPROP 2 LASTPIN (-3600 2275) $PN J10
J 2
(-3610 2285);
DISPLAY 0.617021 (-3610 2285);
PAINT ORANGE (-3610 2285);
FORCEPROP 2 LASTPIN (-3600 2225) $PN L14
J 2
(-3610 2235);
DISPLAY 0.617021 (-3610 2235);
PAINT ORANGE (-3610 2235);
FORCEPROP 2 LASTPIN (-3600 2175) $PN L16
J 2
(-3610 2185);
DISPLAY 0.617021 (-3610 2185);
PAINT ORANGE (-3610 2185);
FORCEPROP 2 LASTPIN (-3600 2125) $PN DH7
J 2
(-3610 2135);
DISPLAY 0.617021 (-3610 2135);
PAINT ORANGE (-3610 2135);
FORCEPROP 2 LASTPIN (-3600 2075) $PN DG8
J 2
(-3610 2085);
DISPLAY 0.617021 (-3610 2085);
PAINT ORANGE (-3610 2085);
FORCEPROP 2 LASTPIN (-3600 2025) $PN M11
J 2
(-3610 2035);
DISPLAY 0.617021 (-3610 2035);
PAINT ORANGE (-3610 2035);
FORCEPROP 2 LASTPIN (-3600 1975) $PN M21
J 2
(-3610 1985);
DISPLAY 0.617021 (-3610 1985);
PAINT ORANGE (-3610 1985);
FORCEPROP 2 LASTPIN (-3600 1925) $PN P5
J 2
(-3610 1935);
DISPLAY 0.617021 (-3610 1935);
PAINT ORANGE (-3610 1935);
FORCEPROP 2 LASTPIN (-3600 1875) $PN T3
J 2
(-3610 1885);
DISPLAY 0.617021 (-3610 1885);
PAINT ORANGE (-3610 1885);
FORCEPROP 2 LASTPIN (-3600 1825) $PN U14
J 2
(-3610 1835);
DISPLAY 0.617021 (-3610 1835);
PAINT ORANGE (-3610 1835);
FORCEPROP 2 LASTPIN (-3600 1775) $PN DF21
J 2
(-3610 1785);
DISPLAY 0.617021 (-3610 1785);
PAINT ORANGE (-3610 1785);
FORCEPROP 2 LASTPIN (-3600 1725) $PN W4
J 2
(-3610 1735);
DISPLAY 0.617021 (-3610 1735);
PAINT ORANGE (-3610 1735);
FORCEPROP 2 LASTPIN (-3600 1675) $PN W6
J 2
(-3610 1685);
DISPLAY 0.617021 (-3610 1685);
PAINT ORANGE (-3610 1685);
FORCEPROP 2 LASTPIN (-3600 1625) $PN AA10
J 2
(-3610 1635);
DISPLAY 0.617021 (-3610 1635);
PAINT ORANGE (-3610 1635);
FORCEPROP 2 LASTPIN (-3600 1575) $PN AC20
J 2
(-3610 1585);
DISPLAY 0.617021 (-3610 1585);
PAINT ORANGE (-3610 1585);
FORCEPROP 2 LASTPIN (-3600 1525) $PN AC4
J 2
(-3610 1535);
DISPLAY 0.617021 (-3610 1535);
PAINT ORANGE (-3610 1535);
FORCEPROP 2 LASTPIN (-3600 1475) $PN AH9
J 2
(-3610 1485);
DISPLAY 0.617021 (-3610 1485);
PAINT ORANGE (-3610 1485);
FORCEPROP 2 LASTPIN (-3600 1425) $PN DF13
J 2
(-3610 1435);
DISPLAY 0.617021 (-3610 1435);
PAINT ORANGE (-3610 1435);
FORCEPROP 2 LASTPIN (-3600 1375) $PN AN10
J 2
(-3610 1385);
DISPLAY 0.617021 (-3610 1385);
PAINT ORANGE (-3610 1385);
FORCEPROP 2 LASTPIN (-3600 1325) $PN DD7
J 2
(-3610 1335);
DISPLAY 0.617021 (-3610 1335);
PAINT ORANGE (-3610 1335);
FORCEPROP 2 LASTPIN (-3600 1275) $PN AT11
J 2
(-3610 1285);
DISPLAY 0.617021 (-3610 1285);
PAINT ORANGE (-3610 1285);
FORCEPROP 2 LASTPIN (-3600 1225) $PN AW6
J 2
(-3610 1235);
DISPLAY 0.617021 (-3610 1235);
PAINT ORANGE (-3610 1235);
FORCEPROP 2 LASTPIN (-3600 1175) $PN AY11
J 2
(-3610 1185);
DISPLAY 0.617021 (-3610 1185);
PAINT ORANGE (-3610 1185);
FORCEPROP 2 LASTPIN (-3600 1125) $PN BA24
J 2
(-3610 1135);
DISPLAY 0.617021 (-3610 1135);
PAINT ORANGE (-3610 1135);
FORCEPROP 2 LASTPIN (-3600 1075) $PN BB5
J 2
(-3610 1085);
DISPLAY 0.617021 (-3610 1085);
PAINT ORANGE (-3610 1085);
FORCEPROP 2 LASTPIN (-3600 1025) $PN DA14
J 2
(-3610 1035);
DISPLAY 0.617021 (-3610 1035);
PAINT ORANGE (-3610 1035);
FORCEPROP 2 LASTPIN (-3600 975) $PN BF23
J 2
(-3610 985);
DISPLAY 0.617021 (-3610 985);
PAINT ORANGE (-3610 985);
FORCEPROP 2 LASTPIN (-3600 925) $PN BJ24
J 2
(-3610 935);
DISPLAY 0.617021 (-3610 935);
PAINT ORANGE (-3610 935);
FORCEPROP 2 LASTPIN (-3600 875) $PN BP25
J 2
(-3610 885);
DISPLAY 0.617021 (-3610 885);
PAINT ORANGE (-3610 885);
FORCEPROP 2 LASTPIN (-1800 875) $PN CE18
J 0
(-1790 885);
DISPLAY 0.617021 (-1790 885);
PAINT ORANGE (-1790 885);
FORCEPROP 2 LASTPIN (-1800 825) $PN D7
J 0
(-1790 835);
DISPLAY 0.617021 (-1790 835);
PAINT ORANGE (-1790 835);
FORCEPROP 2 LASTPIN (-1800 775) $PN CH9
J 0
(-1790 785);
DISPLAY 0.617021 (-1790 785);
PAINT ORANGE (-1790 785);
FORCEPROP 2 LASTPIN (-1800 675) $PN CV7
J 0
(-1790 685);
DISPLAY 0.617021 (-1790 685);
PAINT ORANGE (-1790 685);
FORCEPROP 2 LASTPIN (-1800 625) $PN CK5
J 0
(-1790 635);
DISPLAY 0.617021 (-1790 635);
PAINT ORANGE (-1790 635);
FORCEPROP 2 LASTPIN (-1800 575) $PN CL12
J 0
(-1790 585);
DISPLAY 0.617021 (-1790 585);
PAINT ORANGE (-1790 585);
FORCEPROP 2 LASTPIN (-1800 525) $PN CM15
J 0
(-1790 535);
DISPLAY 0.617021 (-1790 535);
PAINT ORANGE (-1790 535);
FORCEPROP 2 LASTPIN (-1800 1625) $PN A8
J 0
(-1790 1635);
DISPLAY 0.617021 (-1790 1635);
PAINT ORANGE (-1790 1635);
FORCEPROP 2 LASTPIN (-1800 1575) $PN A10
J 0
(-1790 1585);
DISPLAY 0.617021 (-1790 1585);
PAINT ORANGE (-1790 1585);
FORCEPROP 2 LASTPIN (-1800 1525) $PN A12
J 0
(-1790 1535);
DISPLAY 0.617021 (-1790 1535);
PAINT ORANGE (-1790 1535);
FORCEPROP 2 LASTPIN (-1800 1475) $PN B11
J 0
(-1790 1485);
DISPLAY 0.617021 (-1790 1485);
PAINT ORANGE (-1790 1485);
FORCEPROP 2 LASTPIN (-1800 2525) $PN BM11
J 0
(-1790 2535);
DISPLAY 0.617021 (-1790 2535);
PAINT ORANGE (-1790 2535);
FORCEPROP 2 LASTPIN (-1800 2475) $PN BN12
J 0
(-1790 2485);
DISPLAY 0.617021 (-1790 2485);
PAINT ORANGE (-1790 2485);
FORCEPROP 2 LASTPIN (-1800 2425) $PN BN14
J 0
(-1790 2435);
DISPLAY 0.617021 (-1790 2435);
PAINT ORANGE (-1790 2435);
FORCEPROP 2 LASTPIN (-1800 2375) $PN BP11
J 0
(-1790 2385);
DISPLAY 0.617021 (-1790 2385);
PAINT ORANGE (-1790 2385);
FORCEPROP 2 LASTPIN (-1800 2325) $PN BP13
J 0
(-1790 2335);
DISPLAY 0.617021 (-1790 2335);
PAINT ORANGE (-1790 2335);
FORCEPROP 2 LASTPIN (-1800 2275) $PN BP15
J 0
(-1790 2285);
DISPLAY 0.617021 (-1790 2285);
PAINT ORANGE (-1790 2285);
FORCEPROP 2 LASTPIN (-1800 2125) $PN BR14
J 0
(-1790 2135);
DISPLAY 0.617021 (-1790 2135);
PAINT ORANGE (-1790 2135);
FORCEPROP 2 LASTPIN (-1800 2075) $PN BT11
J 0
(-1790 2085);
DISPLAY 0.617021 (-1790 2085);
PAINT ORANGE (-1790 2085);
FORCEPROP 2 LASTPIN (-1800 2025) $PN BT13
J 0
(-1790 2035);
DISPLAY 0.617021 (-1790 2035);
PAINT ORANGE (-1790 2035);
FORCEPROP 2 LASTPIN (-1800 1975) $PN BT15
J 0
(-1790 1985);
DISPLAY 0.617021 (-1790 1985);
PAINT ORANGE (-1790 1985);
FORCEPROP 2 LASTPIN (-1800 1925) $PN BU12
J 0
(-1790 1935);
DISPLAY 0.617021 (-1790 1935);
PAINT ORANGE (-1790 1935);
FORCEPROP 2 LASTPIN (-1800 1875) $PN BU14
J 0
(-1790 1885);
DISPLAY 0.617021 (-1790 1885);
PAINT ORANGE (-1790 1885);
FORCEPROP 2 LASTPIN (-1800 1825) $PN BV11
J 0
(-1790 1835);
DISPLAY 0.617021 (-1790 1835);
PAINT ORANGE (-1790 1835);
FORCEPROP 2 LASTPIN (-1800 1775) $PN BV13
J 0
(-1790 1785);
DISPLAY 0.617021 (-1790 1785);
PAINT ORANGE (-1790 1785);
FORCEPROP 2 LASTPIN (-1800 1725) $PN BV15
J 0
(-1790 1735);
DISPLAY 0.617021 (-1790 1735);
PAINT ORANGE (-1790 1735);
FORCEPROP 2 LASTPIN (-1800 1325) $PN BV27
J 0
(-1790 1335);
DISPLAY 0.617021 (-1790 1335);
PAINT ORANGE (-1790 1335);
FORCEPROP 2 LASTPIN (-1800 1275) $PN BU26
J 0
(-1790 1285);
DISPLAY 0.617021 (-1790 1285);
PAINT ORANGE (-1790 1285);
FORCEPROP 2 LASTPIN (-1800 1225) $PN BT27
J 0
(-1790 1235);
DISPLAY 0.617021 (-1790 1235);
PAINT ORANGE (-1790 1235);
FORCEPROP 2 LASTPIN (-1800 3225) $PN BD13
J 0
(-1790 3235);
DISPLAY 0.617021 (-1790 3235);
PAINT ORANGE (-1790 3235);
FORCEPROP 2 LASTPIN (-1800 3175) $PN BE12
J 0
(-1790 3185);
DISPLAY 0.617021 (-1790 3185);
PAINT ORANGE (-1790 3185);
FORCEPROP 2 LASTPIN (-1800 3125) $PN BE14
J 0
(-1790 3135);
DISPLAY 0.617021 (-1790 3135);
PAINT ORANGE (-1790 3135);
FORCEPROP 2 LASTPIN (-1800 3075) $PN BF11
J 0
(-1790 3085);
DISPLAY 0.617021 (-1790 3085);
PAINT ORANGE (-1790 3085);
FORCEPROP 2 LASTPIN (-1800 3025) $PN BF13
J 0
(-1790 3035);
DISPLAY 0.617021 (-1790 3035);
PAINT ORANGE (-1790 3035);
FORCEPROP 2 LASTPIN (-1800 2975) $PN BG12
J 0
(-1790 2985);
DISPLAY 0.617021 (-1790 2985);
PAINT ORANGE (-1790 2985);
FORCEPROP 2 LASTPIN (-1800 2925) $PN BG14
J 0
(-1790 2935);
DISPLAY 0.617021 (-1790 2935);
PAINT ORANGE (-1790 2935);
FORCEPROP 2 LASTPIN (-1800 2875) $PN BH13
J 0
(-1790 2885);
DISPLAY 0.617021 (-1790 2885);
PAINT ORANGE (-1790 2885);
FORCEPROP 2 LASTPIN (-1800 2825) $PN BJ12
J 0
(-1790 2835);
DISPLAY 0.617021 (-1790 2835);
PAINT ORANGE (-1790 2835);
FORCEPROP 2 LASTPIN (-1800 2775) $PN BJ14
J 0
(-1790 2785);
DISPLAY 0.617021 (-1790 2785);
PAINT ORANGE (-1790 2785);
FORCEPROP 2 LASTPIN (-1800 2725) $PN BK13
J 0
(-1790 2735);
DISPLAY 0.617021 (-1790 2735);
PAINT ORANGE (-1790 2735);
FORCEPROP 2 LASTPIN (-1800 2675) $PN BK15
J 0
(-1790 2685);
DISPLAY 0.617021 (-1790 2685);
PAINT ORANGE (-1790 2685);
FORCEPROP 2 LASTPIN (-1800 2625) $PN BL14
J 0
(-1790 2635);
DISPLAY 0.617021 (-1790 2635);
PAINT ORANGE (-1790 2635);
FORCEPROP 2 LASTPIN (-3600 2325) $PN H13
J 2
(-3610 2335);
DISPLAY 0.617021 (-3610 2335);
PAINT ORANGE (-3610 2335);
FORCEPROP 2 LASTPIN (-1800 1125) $PN CY55
J 0
(-1790 1135);
DISPLAY 0.617021 (-1790 1135);
PAINT ORANGE (-1790 1135);
FORCEPROP 2 LASTPIN (-1800 1025) $PN CB13
J 0
(-1790 1035);
DISPLAY 0.617021 (-1790 1035);
PAINT ORANGE (-1790 1035);
FORCEPROP 2 LASTPIN (-1800 975) $PN CB17
J 0
(-1790 985);
DISPLAY 0.617021 (-1790 985);
PAINT ORANGE (-1790 985);
FORCEPROP 2 LASTPIN (-1800 925) $PN CD9
J 0
(-1790 935);
DISPLAY 0.617021 (-1790 935);
PAINT ORANGE (-1790 935);
FORCEPROP 2 LASTPIN (-1800 1375) $PN BY27
J 0
(-1790 1385);
DISPLAY 0.617021 (-1790 1385);
PAINT ORANGE (-1790 1385);
FORCEPROP 2 LASTPIN (-1800 2175) $PN BR12
J 0
(-1790 2185);
DISPLAY 0.617021 (-1790 2185);
PAINT ORANGE (-1790 2185);
FORCEPROP 1 LAST PACK_TYPE BGA1
J 0
(-3550 4875);
PAINT SKYBLUE (-3550 4875);
DISPLAY INVISIBLE (-3550 4875);
FORCEPROP 2 LAST SEC_TYPE BGA1
J 0
(-3550 4875);
DISPLAY 1.021277 (-3550 4875);
PAINT ORANGE (-3550 4875);
DISPLAY INVISIBLE (-3550 4875);
FORCEPROP 2 LAST CDS_LIB chpset_lib
J 0
(-2700 2575);
PAINT ORANGE (-2700 2575);
DISPLAY INVISIBLE (-2700 2575);
FORCEPROP 2 LAST SEC 21
J 0
(-3550 4875);
DISPLAY 0.680851 (-3550 4875);
PAINT MONO (-3550 4875);
DISPLAY INVISIBLE (-3550 4875);
FORCEPROP 2 LAST CDS_LOCATION U2D1
J 0
(-3550 4825);
DISPLAY 0.617021 (-3550 4825);
PAINT AQUA (-3550 4825);
DISPLAY INVISIBLE (-3550 4825);
FORCEPROP 1 LAST PATH I33
J 0
(-2700 4775);
PAINT GREEN (-2700 4775);
DISPLAY INVISIBLE (-2700 4775);
FORCEADD PVPP_GHJ..1
(-1425 1925);
FORCEPROP 3 LASTPIN (-1425 1875) SIG_NAME PVPP_GHJ\g
J 0
(-1415 1885);
DISPLAY 0.659574 (-1415 1885);
PAINT MONO (-1415 1885);
DISPLAY INVISIBLE (-1415 1885);
FORCEPROP 1 LAST VOLTAGE 2.5V
J 0
(-1470 1882);
DISPLAY 0.340426 (-1470 1882);
PAINT SKYBLUE (-1470 1882);
DISPLAY INVISIBLE (-1470 1882);
FORCEPROP 2 LAST BOM_COST PVPP_KLM_VR
J 0
(-1350 2025);
PAINT MONO (-1350 2025);
DISPLAY INVISIBLE (-1350 2025);
FORCEPROP 2 LAST CDS_LIB mstr_symbols
J 0
(-1425 1925);
PAINT ORANGE (-1425 1925);
DISPLAY INVISIBLE (-1425 1925);
FORCEPROP 1 LAST BODY_TYPE PLUMBING
J 0
(-1470 1882);
DISPLAY 0.340426 (-1470 1882);
PAINT GREEN (-1470 1882);
DISPLAY INVISIBLE (-1470 1882);
FORCEPROP 1 LAST PATH I38
J 0
(-1375 1950);
DISPLAY 0.872340 (-1375 1950);
PAINT AQUA (-1375 1950);
DISPLAY INVISIBLE (-1375 1950);
FORCEPROP 2 LAST ROOM PVPP_KLM_VR
J 0
(-1175 2025);
PAINT ORANGE (-1175 2025);
DISPLAY INVISIBLE (-1175 2025);
FORCEPROP 1 LAST HDL_POWER PVPP_GHJ
J 1
(-1425 1975);
DISPLAY 0.872340 (-1425 1975);
PAINT GREEN (-1425 1975);
DISPLAY INVISIBLE (-1425 1975);
FORCEADD VCC_CORE..1
(-700 1425);
FORCEPROP 3 LASTPIN (-700 1375) SIG_NAME P1V8_MCP_CPU1\g
J 0
(-690 1385);
DISPLAY 0.659574 (-690 1385);
PAINT MONO (-690 1385);
DISPLAY INVISIBLE (-690 1385);
FORCEPROP 1 LAST HDL_POWER P1V8_MCP_CPU1
J 1
(-700 1475);
DISPLAY 0.617021 (-700 1475);
PAINT GREEN (-700 1475);
FORCEPROP 1 LAST PATH I39
J 0
(-650 1450);
DISPLAY 0.872340 (-650 1450);
PAINT AQUA (-650 1450);
DISPLAY INVISIBLE (-650 1450);
FORCEPROP 2 LAST CDS_LIB mstr_symbols
J 0
(-700 1425);
PAINT ORANGE (-700 1425);
DISPLAY INVISIBLE (-700 1425);
FORCEPROP 0 LAST VOLTAGE 1.8
J 0
(-700 1575);
DISPLAY 1.021277 (-700 1575);
PAINT SKYBLUE (-700 1575);
DISPLAY INVISIBLE (-700 1575);
FORCEADD P3V3_STBY..1
(-1200 1225);
FORCEPROP 3 LASTPIN (-1200 1175) SIG_NAME P3V3_STBY\g
J 0
(-1190 1185);
DISPLAY 0.659574 (-1190 1185);
PAINT MONO (-1190 1185);
DISPLAY INVISIBLE (-1190 1185);
FORCEPROP 1 LAST VOLTAGE 3.3V
J 0
(-1245 1182);
DISPLAY 0.340426 (-1245 1182);
PAINT SKYBLUE (-1245 1182);
DISPLAY INVISIBLE (-1245 1182);
FORCEPROP 1 LAST SIZE 1B
J 0
(-1155 1247);
DISPLAY 0.340426 (-1155 1247);
PAINT GREEN (-1155 1247);
DISPLAY INVISIBLE (-1155 1247);
FORCEPROP 2 LAST CDS_LIB mstr_symbols
J 0
(-1200 1225);
PAINT ORANGE (-1200 1225);
DISPLAY INVISIBLE (-1200 1225);
FORCEPROP 1 LAST BODY_TYPE PLUMBING
J 0
(-1245 1182);
DISPLAY 0.340426 (-1245 1182);
PAINT GREEN (-1245 1182);
DISPLAY INVISIBLE (-1245 1182);
FORCEPROP 1 LAST PATH I40
J 0
(-1155 1227);
DISPLAY 0.340426 (-1155 1227);
PAINT GREEN (-1155 1227);
DISPLAY INVISIBLE (-1155 1227);
FORCEPROP 1 LAST HDL_POWER P3V3_STBY
J 0
(-1500 1100);
DISPLAY 0.872340 (-1500 1100);
PAINT ORANGE (-1500 1100);
DISPLAY INVISIBLE (-1500 1100);
FORCEADD DESIGN_NOTE..1
(-5575 800);
FORCEPROP 0 LAST L1 CPU SYMBOLS 1-30 ARE PRELIMINARY AND SUBJECT TO CHANGE
J 0
(-5775 675);
DISPLAY 1.021277 (-5775 675);
PAINT ORANGE (-5775 675);
FORCEPROP 2 LAST CDS_LIB mstr_symbols
J 0
(-5575 800);
PAINT ORANGE (-5575 800);
DISPLAY INVISIBLE (-5575 800);
FORCEPROP 1 LAST COMMENT_BODY TRUE
J 0
(-5550 900);
DISPLAY 0.978723 (-5550 900);
PAINT ORANGE (-5550 900);
DISPLAY INVISIBLE (-5550 900);
FORCEADD PRELIM..10
(-2690 2565);
PAINT GRAY (-2690 2565);
FORCEPROP 2 LAST CDS_LIB mstr_misc
J 0
(-2690 2565);
PAINT ORANGE (-2690 2565);
DISPLAY INVISIBLE (-2690 2565);
FORCEPROP 1 LAST COMMENT_BODY TRUE
J 0
(-2690 2565);
PAINT ORANGE (-2690 2565);
DISPLAY INVISIBLE (-2690 2565);
FORCEADD INTEL_CORP_BPAGE..1
(0 0);
FORCEPROP 1 LAST CDS_CON_LAST_MODIFIED Fri Jun 16 17:48:26 2017
J 0
(-1425 325);
DISPLAY 1.340426 (-1425 325);
PAINT GREEN (-1425 325);
DISPLAY INVISIBLE (-1425 325);
FORCEPROP 1 LAST CUSTOM_TXT_CDS <CURRENT_DESIGN_SHEET> OF <TOTAL_DESIGN_SHEETS>
J 0
(-500 25);
PAINT ORANGE (-500 25);
FORCEPROP 1 LAST CUSTOM_TXT_CDS <CON_LAST_MODIFIED>
J 0
(-4000 100);
PAINT ORANGE (-4000 100);
FORCEPROP 2 LAST CUSTOM_TXT_CDS <XR_PAGE_TITLE>
J 0
(-7890 5250);
DISPLAY 0.638298 (-7890 5250);
PAINT PINK (-7890 5250);
DISPLAY INVISIBLE (-7890 5250);
FORCEPROP 1 LAST SCH_TITLE SKYLAKE - SKT1 - 18 OF 21
J 0
(-7950 50);
DISPLAY 1.212766 (-7950 50);
PAINT GREEN (-7950 50);
FORCEPROP 2 LAST PAGE_BORDER TRUE
J 0
(-7890 5250);
DISPLAY 0.851064 (-7890 5250);
PAINT PINK (-7890 5250);
DISPLAY INVISIBLE (-7890 5250);
FORCEPROP 2 LAST CDS_LIB mstr_symbols
J 0
(0 0);
PAINT ORANGE (0 0);
DISPLAY INVISIBLE (0 0);
FORCEPROP 1 LAST COMMENT_BODY TRUE
J 0
(12 12);
DISPLAY 0.638298 (12 12);
PAINT GREEN (12 12);
DISPLAY INVISIBLE (12 12);
FORCEPROP 2 LAST CDS_XR_PAGE_TITLE CR-72 : @BASEBOARD_FAB2_LIB.BASEBOARD_FAB2(SCH_1):PAGE72
J 0
(-7890 5250);
DISPLAY 0.638298 (-7890 5250);
PAINT PINK (-7890 5250);
DISPLAY INVISIBLE (-7890 5250);
WIRE 16 -1 (-7325 3850)(-7325 4200);
WIRE 16 -1 (-7325 3850)(-7325 3800);
WIRE 16 -1 (-7325 3850)(-7050 3850);
WIRE 16 -1 (-7325 3800)(-7325 3750);
WIRE 16 -1 (-7325 3800)(-7050 3800);
WIRE 16 -1 (-7325 3750)(-7325 3700);
WIRE 16 -1 (-7325 3750)(-7050 3750);
WIRE 16 -1 (-7325 3700)(-7325 3650);
WIRE 16 -1 (-7325 3700)(-7050 3700);
WIRE 16 -1 (-7325 3650)(-7325 3600);
WIRE 16 -1 (-7325 3650)(-7050 3650);
WIRE 16 -1 (-7325 3600)(-7325 3550);
WIRE 16 -1 (-7325 3600)(-7050 3600);
WIRE 16 -1 (-7325 3550)(-7325 3500);
WIRE 16 -1 (-7325 3550)(-7050 3550);
WIRE 16 -1 (-7325 3500)(-7325 3450);
WIRE 16 -1 (-7325 3500)(-7050 3500);
WIRE 16 -1 (-7325 3450)(-7325 3400);
WIRE 16 -1 (-7325 3450)(-7050 3450);
WIRE 16 -1 (-7325 3400)(-7325 3350);
WIRE 16 -1 (-7325 3400)(-7050 3400);
WIRE 16 -1 (-7325 3350)(-7325 3300);
WIRE 16 -1 (-7325 3350)(-7050 3350);
WIRE 16 -1 (-7325 3300)(-7325 3250);
WIRE 16 -1 (-7325 3300)(-7050 3300);
WIRE 16 -1 (-7325 3250)(-7325 3200);
WIRE 16 -1 (-7325 3250)(-7050 3250);
WIRE 16 -1 (-7325 3200)(-7325 3150);
WIRE 16 -1 (-7325 3200)(-7050 3200);
WIRE 16 -1 (-7325 3150)(-7325 3100);
WIRE 16 -1 (-7325 3150)(-7050 3150);
WIRE 16 -1 (-7325 3100)(-7325 3050);
WIRE 16 -1 (-7325 3100)(-7050 3100);
WIRE 16 -1 (-7325 3050)(-7325 3000);
WIRE 16 -1 (-7325 3050)(-7050 3050);
WIRE 16 -1 (-7325 3000)(-7325 2950);
WIRE 16 -1 (-7325 3000)(-7050 3000);
WIRE 16 -1 (-7325 2950)(-7325 2900);
WIRE 16 -1 (-7325 2950)(-7050 2950);
WIRE 16 -1 (-7325 2900)(-7325 2850);
WIRE 16 -1 (-7325 2900)(-7050 2900);
WIRE 16 -1 (-7325 2850)(-7325 2800);
WIRE 16 -1 (-7325 2850)(-7050 2850);
WIRE 16 -1 (-7325 2800)(-7325 2750);
WIRE 16 -1 (-7325 2800)(-7050 2800);
WIRE 16 -1 (-7325 2750)(-7325 2700);
WIRE 16 -1 (-7325 2750)(-7050 2750);
WIRE 16 -1 (-7325 2700)(-7325 2650);
WIRE 16 -1 (-7325 2700)(-7050 2700);
WIRE 16 -1 (-7325 2650)(-7325 2600);
WIRE 16 -1 (-7325 2650)(-7050 2650);
WIRE 16 -1 (-7325 2600)(-7325 2550);
WIRE 16 -1 (-7325 2600)(-7050 2600);
WIRE 16 -1 (-7325 2550)(-7325 2500);
WIRE 16 -1 (-7325 2550)(-7050 2550);
WIRE 16 -1 (-7325 2500)(-7325 2450);
WIRE 16 -1 (-7325 2500)(-7050 2500);
WIRE 16 -1 (-7325 2450)(-7325 2400);
WIRE 16 -1 (-7325 2450)(-7050 2450);
WIRE 16 -1 (-7325 2400)(-7325 2350);
WIRE 16 -1 (-7325 2400)(-7050 2400);
WIRE 16 -1 (-7325 2350)(-7325 2300);
WIRE 16 -1 (-7325 2350)(-7050 2350);
WIRE 16 -1 (-7325 2300)(-7325 2250);
WIRE 16 -1 (-7325 2300)(-7050 2300);
WIRE 16 -1 (-7325 2250)(-7325 2200);
WIRE 16 -1 (-7325 2250)(-7050 2250);
WIRE 16 -1 (-7325 2200)(-7325 2150);
WIRE 16 -1 (-7325 2200)(-7050 2200);
WIRE 16 -1 (-7325 2150)(-7325 2100);
WIRE 16 -1 (-7325 2150)(-7050 2150);
WIRE 16 -1 (-7325 2100)(-7325 2050);
WIRE 16 -1 (-7325 2100)(-7050 2100);
WIRE 16 -1 (-7325 2050)(-7325 2000);
WIRE 16 -1 (-7325 2050)(-7050 2050);
WIRE 16 -1 (-7325 2000)(-7325 1950);
WIRE 16 -1 (-7325 2000)(-7050 2000);
WIRE 16 -1 (-7325 1950)(-7325 1900);
WIRE 16 -1 (-7325 1950)(-7050 1950);
WIRE 16 -1 (-7325 1900)(-7325 1850);
WIRE 16 -1 (-7325 1900)(-7050 1900);
WIRE 16 -1 (-7325 1850)(-7325 1800);
WIRE 16 -1 (-7325 1850)(-7050 1850);
WIRE 16 -1 (-7325 1800)(-7325 1750);
WIRE 16 -1 (-7325 1800)(-7050 1800);
WIRE 16 -1 (-7325 1750)(-7325 1700);
WIRE 16 -1 (-7325 1750)(-7050 1750);
WIRE 16 -1 (-7325 1700)(-7325 1650);
WIRE 16 -1 (-7325 1700)(-7050 1700);
WIRE 16 -1 (-7325 1650)(-7325 1600);
WIRE 16 -1 (-7325 1650)(-7050 1650);
WIRE 16 -1 (-7325 1600)(-7325 1550);
WIRE 16 -1 (-7325 1600)(-7050 1600);
WIRE 16 -1 (-7325 1550)(-7325 1500);
WIRE 16 -1 (-7325 1550)(-7050 1550);
WIRE 16 -1 (-7325 1500)(-7325 1450);
WIRE 16 -1 (-7325 1500)(-7050 1500);
WIRE 16 -1 (-7325 1450)(-7325 1350);
WIRE 16 -1 (-7325 1450)(-7050 1450);
WIRE 16 -1 (-7325 1350)(-7325 1300);
WIRE 16 -1 (-7325 1350)(-7050 1350);
WIRE 16 -1 (-7325 1300)(-7325 1250);
WIRE 16 -1 (-7325 1300)(-7050 1300);
WIRE 16 -1 (-7325 1250)(-7050 1250);
WIRE 16 -1 (-5050 4200)(-5050 3850);
WIRE 16 -1 (-5050 3850)(-5050 3800);
WIRE 16 -1 (-5050 3850)(-5350 3850);
WIRE 16 -1 (-5050 3800)(-5050 3750);
WIRE 16 -1 (-5050 3800)(-5350 3800);
WIRE 16 -1 (-5050 3750)(-5050 3700);
WIRE 16 -1 (-5050 3750)(-5350 3750);
WIRE 16 -1 (-5050 3700)(-5050 3650);
WIRE 16 -1 (-5050 3700)(-5350 3700);
WIRE 16 -1 (-5050 3650)(-5050 3600);
WIRE 16 -1 (-5050 3650)(-5350 3650);
WIRE 16 -1 (-5050 3600)(-5050 3550);
WIRE 16 -1 (-5050 3600)(-5350 3600);
WIRE 16 -1 (-5050 3550)(-5050 3500);
WIRE 16 -1 (-5050 3550)(-5350 3550);
WIRE 16 -1 (-5050 3500)(-5050 3450);
WIRE 16 -1 (-5050 3500)(-5350 3500);
WIRE 16 -1 (-5050 3450)(-5050 3400);
WIRE 16 -1 (-5050 3450)(-5350 3450);
WIRE 16 -1 (-5050 3400)(-5050 3350);
WIRE 16 -1 (-5050 3400)(-5350 3400);
WIRE 16 -1 (-5050 3350)(-5050 3300);
WIRE 16 -1 (-5050 3350)(-5350 3350);
WIRE 16 -1 (-5050 3300)(-5050 3250);
WIRE 16 -1 (-5050 3300)(-5350 3300);
WIRE 16 -1 (-5050 3250)(-5050 3200);
WIRE 16 -1 (-5050 3250)(-5350 3250);
WIRE 16 -1 (-5050 3200)(-5050 3150);
WIRE 16 -1 (-5050 3200)(-5350 3200);
WIRE 16 -1 (-5050 3150)(-5050 3100);
WIRE 16 -1 (-5050 3150)(-5350 3150);
WIRE 16 -1 (-5050 3100)(-5050 3050);
WIRE 16 -1 (-5050 3100)(-5350 3100);
WIRE 16 -1 (-5050 3050)(-5050 3000);
WIRE 16 -1 (-5050 3050)(-5350 3050);
WIRE 16 -1 (-5050 3000)(-5050 2950);
WIRE 16 -1 (-5050 3000)(-5350 3000);
WIRE 16 -1 (-5050 2950)(-5050 2900);
WIRE 16 -1 (-5050 2950)(-5350 2950);
WIRE 16 -1 (-5050 2900)(-5050 2850);
WIRE 16 -1 (-5050 2900)(-5350 2900);
WIRE 16 -1 (-5050 2850)(-5050 2800);
WIRE 16 -1 (-5050 2850)(-5350 2850);
WIRE 16 -1 (-5050 2800)(-5050 2750);
WIRE 16 -1 (-5050 2800)(-5350 2800);
WIRE 16 -1 (-5050 2750)(-5050 2700);
WIRE 16 -1 (-5050 2750)(-5350 2750);
WIRE 16 -1 (-5050 2700)(-5050 2650);
WIRE 16 -1 (-5050 2700)(-5350 2700);
WIRE 16 -1 (-5050 2650)(-5050 2600);
WIRE 16 -1 (-5050 2650)(-5350 2650);
WIRE 16 -1 (-5050 2600)(-5050 2550);
WIRE 16 -1 (-5050 2600)(-5350 2600);
WIRE 16 -1 (-5050 2550)(-5050 2500);
WIRE 16 -1 (-5050 2550)(-5350 2550);
WIRE 16 -1 (-5050 2500)(-5050 2450);
WIRE 16 -1 (-5050 2500)(-5350 2500);
WIRE 16 -1 (-5050 2450)(-5050 2400);
WIRE 16 -1 (-5050 2450)(-5350 2450);
WIRE 16 -1 (-5050 2400)(-5050 2350);
WIRE 16 -1 (-5050 2400)(-5350 2400);
WIRE 16 -1 (-5050 2350)(-5050 2300);
WIRE 16 -1 (-5050 2350)(-5350 2350);
WIRE 16 -1 (-5050 2300)(-5050 2250);
WIRE 16 -1 (-5050 2300)(-5350 2300);
WIRE 16 -1 (-5050 2250)(-5050 2200);
WIRE 16 -1 (-5050 2250)(-5350 2250);
WIRE 16 -1 (-5050 2200)(-5050 2150);
WIRE 16 -1 (-5050 2200)(-5350 2200);
WIRE 16 -1 (-5050 2150)(-5050 2100);
WIRE 16 -1 (-5050 2150)(-5350 2150);
WIRE 16 -1 (-5050 2100)(-5050 2050);
WIRE 16 -1 (-5050 2100)(-5350 2100);
WIRE 16 -1 (-5050 2050)(-5050 2000);
WIRE 16 -1 (-5050 2050)(-5350 2050);
WIRE 16 -1 (-5050 2000)(-5050 1950);
WIRE 16 -1 (-5050 2000)(-5350 2000);
WIRE 16 -1 (-5050 1950)(-5050 1900);
WIRE 16 -1 (-5050 1950)(-5350 1950);
WIRE 16 -1 (-5050 1900)(-5050 1850);
WIRE 16 -1 (-5050 1900)(-5350 1900);
WIRE 16 -1 (-5050 1850)(-5050 1800);
WIRE 16 -1 (-5050 1850)(-5350 1850);
WIRE 16 -1 (-5050 1800)(-5050 1750);
WIRE 16 -1 (-5050 1800)(-5350 1800);
WIRE 16 -1 (-5050 1750)(-5050 1700);
WIRE 16 -1 (-5050 1750)(-5350 1750);
WIRE 16 -1 (-5050 1700)(-5050 1650);
WIRE 16 -1 (-5050 1700)(-5350 1700);
WIRE 16 -1 (-5050 1650)(-5050 1600);
WIRE 16 -1 (-5050 1650)(-5350 1650);
WIRE 16 -1 (-5050 1600)(-5050 1550);
WIRE 16 -1 (-5050 1600)(-5350 1600);
WIRE 16 -1 (-5050 1550)(-5050 1500);
WIRE 16 -1 (-5050 1550)(-5350 1550);
WIRE 16 -1 (-5050 1500)(-5050 1450);
WIRE 16 -1 (-5050 1500)(-5350 1500);
WIRE 16 -1 (-5050 1450)(-5050 1350);
WIRE 16 -1 (-5050 1450)(-5350 1450);
WIRE 16 -1 (-5050 1350)(-5050 1300);
WIRE 16 -1 (-5050 1350)(-5350 1350);
WIRE 16 -1 (-5050 1300)(-5350 1300);
WIRE 16 -1 (-3850 4800)(-3850 4575);
WIRE 16 -1 (-3850 4575)(-3850 4525);
WIRE 16 -1 (-3600 4575)(-3850 4575);
WIRE 16 -1 (-3850 4525)(-3850 4475);
WIRE 16 -1 (-3600 4525)(-3850 4525);
WIRE 16 -1 (-3850 4475)(-3850 4425);
WIRE 16 -1 (-3600 4475)(-3850 4475);
WIRE 16 -1 (-3850 4425)(-3850 4375);
WIRE 16 -1 (-3600 4425)(-3850 4425);
WIRE 16 -1 (-3850 4375)(-3850 4325);
WIRE 16 -1 (-3600 4375)(-3850 4375);
WIRE 16 -1 (-3850 4325)(-3850 4275);
WIRE 16 -1 (-3600 4325)(-3850 4325);
WIRE 16 -1 (-3850 4275)(-3850 4225);
WIRE 16 -1 (-3600 4275)(-3850 4275);
WIRE 16 -1 (-3850 4225)(-3850 4175);
WIRE 16 -1 (-3600 4225)(-3850 4225);
WIRE 16 -1 (-3850 4175)(-3850 4125);
WIRE 16 -1 (-3600 4175)(-3850 4175);
WIRE 16 -1 (-3850 4125)(-3850 4075);
WIRE 16 -1 (-3600 4125)(-3850 4125);
WIRE 16 -1 (-3850 4075)(-3850 4025);
WIRE 16 -1 (-3600 4075)(-3850 4075);
WIRE 16 -1 (-3850 4025)(-3850 3975);
WIRE 16 -1 (-3600 4025)(-3850 4025);
WIRE 16 -1 (-3850 3975)(-3850 3925);
WIRE 16 -1 (-3600 3975)(-3850 3975);
WIRE 16 -1 (-3850 3925)(-3850 3875);
WIRE 16 -1 (-3600 3925)(-3850 3925);
WIRE 16 -1 (-3850 3875)(-3850 3825);
WIRE 16 -1 (-3600 3875)(-3850 3875);
WIRE 16 -1 (-3850 3825)(-3850 3775);
WIRE 16 -1 (-3600 3825)(-3850 3825);
WIRE 16 -1 (-3850 3775)(-3850 3725);
WIRE 16 -1 (-3600 3775)(-3850 3775);
WIRE 16 -1 (-3850 3725)(-3850 3675);
WIRE 16 -1 (-3600 3725)(-3850 3725);
WIRE 16 -1 (-3850 3675)(-3850 3625);
WIRE 16 -1 (-3600 3675)(-3850 3675);
WIRE 16 -1 (-3850 3625)(-3850 3575);
WIRE 16 -1 (-3600 3625)(-3850 3625);
WIRE 16 -1 (-3850 3575)(-3850 3525);
WIRE 16 -1 (-3600 3575)(-3850 3575);
WIRE 16 -1 (-3850 3525)(-3850 3475);
WIRE 16 -1 (-3600 3525)(-3850 3525);
WIRE 16 -1 (-3850 3475)(-3850 3425);
WIRE 16 -1 (-3600 3475)(-3850 3475);
WIRE 16 -1 (-3850 3425)(-3850 3375);
WIRE 16 -1 (-3600 3425)(-3850 3425);
WIRE 16 -1 (-3850 3375)(-3850 3325);
WIRE 16 -1 (-3600 3375)(-3850 3375);
WIRE 16 -1 (-3850 3325)(-3850 3275);
WIRE 16 -1 (-3600 3325)(-3850 3325);
WIRE 16 -1 (-3850 3275)(-3850 3225);
WIRE 16 -1 (-3600 3275)(-3850 3275);
WIRE 16 -1 (-3850 3225)(-3850 3175);
WIRE 16 -1 (-3600 3225)(-3850 3225);
WIRE 16 -1 (-3850 3175)(-3850 3125);
WIRE 16 -1 (-3600 3175)(-3850 3175);
WIRE 16 -1 (-3850 3125)(-3850 3075);
WIRE 16 -1 (-3600 3125)(-3850 3125);
WIRE 16 -1 (-3850 3075)(-3850 3025);
WIRE 16 -1 (-3600 3075)(-3850 3075);
WIRE 16 -1 (-3850 3025)(-3850 2975);
WIRE 16 -1 (-3600 3025)(-3850 3025);
WIRE 16 -1 (-3850 2975)(-3850 2925);
WIRE 16 -1 (-3600 2975)(-3850 2975);
WIRE 16 -1 (-3850 2925)(-3850 2875);
WIRE 16 -1 (-3600 2925)(-3850 2925);
WIRE 16 -1 (-3850 2875)(-3850 2825);
WIRE 16 -1 (-3600 2875)(-3850 2875);
WIRE 16 -1 (-3850 2825)(-3850 2775);
WIRE 16 -1 (-3600 2825)(-3850 2825);
WIRE 16 -1 (-3850 2775)(-3850 2725);
WIRE 16 -1 (-3600 2775)(-3850 2775);
WIRE 16 -1 (-3850 2725)(-3850 2675);
WIRE 16 -1 (-3600 2725)(-3850 2725);
WIRE 16 -1 (-3850 2675)(-3850 2625);
WIRE 16 -1 (-3600 2675)(-3850 2675);
WIRE 16 -1 (-3850 2625)(-3850 2575);
WIRE 16 -1 (-3600 2625)(-3850 2625);
WIRE 16 -1 (-3850 2575)(-3850 2525);
WIRE 16 -1 (-3600 2575)(-3850 2575);
WIRE 16 -1 (-3850 2525)(-3850 2475);
WIRE 16 -1 (-3600 2525)(-3850 2525);
WIRE 16 -1 (-3850 2475)(-3850 2425);
WIRE 16 -1 (-3600 2475)(-3850 2475);
WIRE 16 -1 (-3850 2425)(-3850 2375);
WIRE 16 -1 (-3600 2425)(-3850 2425);
WIRE 16 -1 (-3850 2375)(-3850 2325);
WIRE 16 -1 (-3600 2375)(-3850 2375);
WIRE 16 -1 (-3850 2325)(-3850 2275);
WIRE 16 -1 (-3600 2325)(-3850 2325);
WIRE 16 -1 (-3850 2275)(-3850 2225);
WIRE 16 -1 (-3600 2275)(-3850 2275);
WIRE 16 -1 (-3850 2225)(-3850 2175);
WIRE 16 -1 (-3600 2225)(-3850 2225);
WIRE 16 -1 (-3850 2175)(-3850 2125);
WIRE 16 -1 (-3600 2175)(-3850 2175);
WIRE 16 -1 (-3850 2125)(-3850 2075);
WIRE 16 -1 (-3600 2125)(-3850 2125);
WIRE 16 -1 (-3850 2075)(-3850 2025);
WIRE 16 -1 (-3600 2075)(-3850 2075);
WIRE 16 -1 (-3850 2025)(-3850 1975);
WIRE 16 -1 (-3600 2025)(-3850 2025);
WIRE 16 -1 (-3850 1975)(-3850 1925);
WIRE 16 -1 (-3600 1975)(-3850 1975);
WIRE 16 -1 (-3850 1925)(-3850 1875);
WIRE 16 -1 (-3600 1925)(-3850 1925);
WIRE 16 -1 (-3850 1875)(-3850 1825);
WIRE 16 -1 (-3600 1875)(-3850 1875);
WIRE 16 -1 (-3850 1825)(-3850 1775);
WIRE 16 -1 (-3600 1825)(-3850 1825);
WIRE 16 -1 (-3850 1775)(-3850 1725);
WIRE 16 -1 (-3600 1775)(-3850 1775);
WIRE 16 -1 (-3850 1725)(-3850 1675);
WIRE 16 -1 (-3600 1725)(-3850 1725);
WIRE 16 -1 (-3850 1675)(-3850 1625);
WIRE 16 -1 (-3600 1675)(-3850 1675);
WIRE 16 -1 (-3850 1625)(-3850 1575);
WIRE 16 -1 (-3600 1625)(-3850 1625);
WIRE 16 -1 (-3850 1575)(-3850 1525);
WIRE 16 -1 (-3600 1575)(-3850 1575);
WIRE 16 -1 (-3850 1525)(-3850 1475);
WIRE 16 -1 (-3600 1525)(-3850 1525);
WIRE 16 -1 (-3850 1475)(-3850 1425);
WIRE 16 -1 (-3600 1475)(-3850 1475);
WIRE 16 -1 (-3850 1425)(-3850 1375);
WIRE 16 -1 (-3600 1425)(-3850 1425);
WIRE 16 -1 (-3850 1375)(-3850 1325);
WIRE 16 -1 (-3600 1375)(-3850 1375);
WIRE 16 -1 (-3850 1325)(-3850 1275);
WIRE 16 -1 (-3600 1325)(-3850 1325);
WIRE 16 -1 (-3850 1275)(-3850 1225);
WIRE 16 -1 (-3600 1275)(-3850 1275);
WIRE 16 -1 (-3850 1225)(-3850 1175);
WIRE 16 -1 (-3600 1225)(-3850 1225);
WIRE 16 -1 (-3850 1175)(-3850 1125);
WIRE 16 -1 (-3600 1175)(-3850 1175);
WIRE 16 -1 (-3850 1075)(-3850 1125);
WIRE 16 -1 (-3600 1125)(-3850 1125);
WIRE 16 -1 (-3850 1075)(-3850 1025);
WIRE 16 -1 (-3600 1075)(-3850 1075);
WIRE 16 -1 (-3850 975)(-3850 1025);
WIRE 16 -1 (-3600 1025)(-3850 1025);
WIRE 16 -1 (-3850 925)(-3850 975);
WIRE 16 -1 (-3600 975)(-3850 975);
WIRE 16 -1 (-3850 875)(-3850 925);
WIRE 16 -1 (-3600 925)(-3850 925);
WIRE 16 -1 (-3600 875)(-3850 875);
WIRE 16 -1 (-1200 1000)(-1200 925);
WIRE 16 -1 (-1450 925)(-1200 925);
WIRE 16 -1 (-1450 925)(-1450 975);
WIRE 16 -1 (-1450 875)(-1450 925);
WIRE 16 -1 (-1450 925)(-1800 925);
WIRE 16 -1 (-1450 825)(-1450 875);
WIRE 16 -1 (-1450 875)(-1800 875);
WIRE 16 -1 (-1450 975)(-1450 1025);
WIRE 16 -1 (-1450 975)(-1800 975);
WIRE 16 -1 (-1450 1025)(-1800 1025);
WIRE 16 -1 (-1450 775)(-1450 825);
WIRE 16 -1 (-1450 825)(-1800 825);
WIRE 16 -1 (-1450 775)(-1450 675);
WIRE 16 -1 (-1450 775)(-1800 775);
WIRE 16 -1 (-1450 675)(-1450 625);
WIRE 16 -1 (-1450 675)(-1800 675);
WIRE 16 -1 (-1450 625)(-1450 575);
WIRE 16 -1 (-1450 625)(-1800 625);
WIRE 16 -1 (-1450 575)(-1450 525);
WIRE 16 -1 (-1450 575)(-1800 575);
WIRE 16 -1 (-1450 525)(-1800 525);
WIRE 16 -1 (-1600 4775)(-1600 4575);
WIRE 16 -1 (-1600 4575)(-1600 4525);
WIRE 16 -1 (-1800 4575)(-1600 4575);
WIRE 16 -1 (-1600 4525)(-1600 4475);
WIRE 16 -1 (-1800 4525)(-1600 4525);
WIRE 16 -1 (-1600 4425)(-1600 4475);
WIRE 16 -1 (-1800 4475)(-1600 4475);
WIRE 16 -1 (-1600 4375)(-1600 4425);
WIRE 16 -1 (-1800 4425)(-1600 4425);
WIRE 16 -1 (-1600 4325)(-1600 4375);
WIRE 16 -1 (-1800 4375)(-1600 4375);
WIRE 16 -1 (-1600 4275)(-1600 4325);
WIRE 16 -1 (-1800 4325)(-1600 4325);
WIRE 16 -1 (-1600 4225)(-1600 4275);
WIRE 16 -1 (-1800 4275)(-1600 4275);
WIRE 16 -1 (-1600 4175)(-1600 4225);
WIRE 16 -1 (-1800 4225)(-1600 4225);
WIRE 16 -1 (-1600 4125)(-1600 4175);
WIRE 16 -1 (-1800 4175)(-1600 4175);
WIRE 16 -1 (-1600 4075)(-1600 4125);
WIRE 16 -1 (-1800 4125)(-1600 4125);
WIRE 16 -1 (-1600 4025)(-1600 4075);
WIRE 16 -1 (-1800 4075)(-1600 4075);
WIRE 16 -1 (-1600 3975)(-1600 4025);
WIRE 16 -1 (-1800 4025)(-1600 4025);
WIRE 16 -1 (-1600 3925)(-1600 3975);
WIRE 16 -1 (-1800 3975)(-1600 3975);
WIRE 16 -1 (-1600 3875)(-1600 3925);
WIRE 16 -1 (-1800 3925)(-1600 3925);
WIRE 16 -1 (-1600 3825)(-1600 3875);
WIRE 16 -1 (-1800 3875)(-1600 3875);
WIRE 16 -1 (-1600 3775)(-1600 3825);
WIRE 16 -1 (-1800 3825)(-1600 3825);
WIRE 16 -1 (-1600 3725)(-1600 3775);
WIRE 16 -1 (-1800 3775)(-1600 3775);
WIRE 16 -1 (-1600 3675)(-1600 3725);
WIRE 16 -1 (-1800 3725)(-1600 3725);
WIRE 16 -1 (-1600 3625)(-1600 3675);
WIRE 16 -1 (-1800 3675)(-1600 3675);
WIRE 16 -1 (-1600 3575)(-1600 3625);
WIRE 16 -1 (-1800 3625)(-1600 3625);
WIRE 16 -1 (-1600 3525)(-1600 3575);
WIRE 16 -1 (-1800 3575)(-1600 3575);
WIRE 16 -1 (-1600 3475)(-1600 3525);
WIRE 16 -1 (-1800 3525)(-1600 3525);
WIRE 16 -1 (-1600 3425)(-1600 3475);
WIRE 16 -1 (-1800 3475)(-1600 3475);
WIRE 16 -1 (-1600 3375)(-1600 3425);
WIRE 16 -1 (-1800 3425)(-1600 3425);
WIRE 16 -1 (-1600 3325)(-1600 3375);
WIRE 16 -1 (-1800 3375)(-1600 3375);
WIRE 16 -1 (-1800 3325)(-1600 3325);
WIRE 16 -1 (-700 1075)(-700 1000);
WIRE 16 -1 (-1250 3250)(-1250 3150);
WIRE 16 -1 (-1600 3150)(-1250 3150);
WIRE 16 -1 (-1600 3125)(-1600 3150);
WIRE 16 -1 (-1600 3150)(-1600 3175);
WIRE 16 -1 (-1600 3175)(-1600 3225);
WIRE 16 -1 (-1800 3175)(-1600 3175);
WIRE 16 -1 (-1600 3125)(-1600 3075);
WIRE 16 -1 (-1800 3125)(-1600 3125);
WIRE 16 -1 (-1600 3075)(-1600 3025);
WIRE 16 -1 (-1800 3075)(-1600 3075);
WIRE 16 -1 (-1800 3225)(-1600 3225);
WIRE 16 -1 (-1600 3025)(-1600 2975);
WIRE 16 -1 (-1800 3025)(-1600 3025);
WIRE 16 -1 (-1600 2975)(-1600 2925);
WIRE 16 -1 (-1800 2975)(-1600 2975);
WIRE 16 -1 (-1600 2925)(-1600 2875);
WIRE 16 -1 (-1800 2925)(-1600 2925);
WIRE 16 -1 (-1600 2875)(-1600 2825);
WIRE 16 -1 (-1800 2875)(-1600 2875);
WIRE 16 -1 (-1600 2825)(-1600 2775);
WIRE 16 -1 (-1800 2825)(-1600 2825);
WIRE 16 -1 (-1600 2775)(-1600 2725);
WIRE 16 -1 (-1800 2775)(-1600 2775);
WIRE 16 -1 (-1600 2725)(-1600 2675);
WIRE 16 -1 (-1800 2725)(-1600 2725);
WIRE 16 -1 (-1600 2675)(-1600 2625);
WIRE 16 -1 (-1800 2675)(-1600 2675);
WIRE 16 -1 (-1800 2625)(-1600 2625);
WIRE 16 -1 (-1250 2525)(-1250 2450);
WIRE 16 -1 (-1250 2450)(-1600 2450);
WIRE 16 -1 (-1600 2425)(-1600 2450);
WIRE 16 -1 (-1600 2450)(-1600 2475);
WIRE 16 -1 (-1600 2525)(-1600 2475);
WIRE 16 -1 (-1800 2475)(-1600 2475);
WIRE 16 -1 (-1600 2425)(-1600 2375);
WIRE 16 -1 (-1800 2425)(-1600 2425);
WIRE 16 -1 (-1600 2375)(-1600 2325);
WIRE 16 -1 (-1800 2375)(-1600 2375);
WIRE 16 -1 (-1800 2525)(-1600 2525);
WIRE 16 -1 (-1600 2325)(-1600 2275);
WIRE 16 -1 (-1800 2325)(-1600 2325);
WIRE 16 -1 (-1600 2175)(-1600 2275);
WIRE 16 -1 (-1800 2275)(-1600 2275);
WIRE 16 -1 (-1600 2175)(-1600 2125);
WIRE 16 -1 (-1800 2175)(-1600 2175);
WIRE 16 -1 (-1600 2125)(-1600 2075);
WIRE 16 -1 (-1800 2125)(-1600 2125);
WIRE 16 -1 (-1600 2075)(-1600 2025);
WIRE 16 -1 (-1800 2075)(-1600 2075);
WIRE 16 -1 (-1600 2025)(-1600 1975);
WIRE 16 -1 (-1800 2025)(-1600 2025);
WIRE 16 -1 (-1600 1975)(-1600 1925);
WIRE 16 -1 (-1800 1975)(-1600 1975);
WIRE 16 -1 (-1600 1925)(-1600 1875);
WIRE 16 -1 (-1800 1925)(-1600 1925);
WIRE 16 -1 (-1600 1875)(-1600 1825);
WIRE 16 -1 (-1800 1875)(-1600 1875);
WIRE 16 -1 (-1600 1825)(-1600 1775);
WIRE 16 -1 (-1800 1825)(-1600 1825);
WIRE 16 -1 (-1600 1775)(-1600 1725);
WIRE 16 -1 (-1800 1775)(-1600 1775);
WIRE 16 -1 (-1800 1725)(-1600 1725);
WIRE 16 -1 (-1425 1625)(-1425 1875);
WIRE 16 -1 (-1425 1575)(-1425 1625);
WIRE 16 -1 (-1800 1625)(-1425 1625);
WIRE 16 -1 (-1425 1525)(-1425 1575);
WIRE 16 -1 (-1800 1575)(-1425 1575);
WIRE 16 -1 (-1425 1475)(-1425 1525);
WIRE 16 -1 (-1800 1525)(-1425 1525);
WIRE 16 -1 (-1800 1475)(-1425 1475);
WIRE 16 -1 (-700 1375)(-700 1325);
WIRE 16 -1 (-1450 1325)(-700 1325);
WIRE 16 -1 (-700 1275)(-700 1325);
WIRE 16 -1 (-1450 1325)(-1450 1375);
WIRE 16 -1 (-1450 1275)(-1450 1325);
WIRE 16 -1 (-1450 1325)(-1800 1325);
WIRE 16 -1 (-1450 1275)(-1450 1225);
WIRE 16 -1 (-1800 1275)(-1450 1275);
WIRE 16 -1 (-1450 1375)(-1800 1375);
WIRE 16 -1 (-1450 1225)(-1800 1225);
WIRE 16 -1 (-1200 1175)(-1200 1125);
WIRE 16 -1 (-1200 1125)(-1800 1125);
WIRE 3 682 (-900 900)(-150 900);
WIRE 3 682 (-900 1550)(-900 900);
WIRE 3 682 (-150 900)(-150 1550);
WIRE 3 682 (-150 1550)(-900 1550);
DOT 1 (-1600 2175);
DOT 1 (-700 1325);
DOT 1 (-1425 1575);
DOT 1 (-3850 3875);
DOT 1 (-1600 4025);
DOT 1 (-1600 2450);
DOT 1 (-3850 3625);
DOT 1 (-5050 3300);
DOT 1 (-7325 2600);
DOT 1 (-3850 3675);
DOT 1 (-3850 2575);
DOT 1 (-1600 1975);
DOT 1 (-1600 2375);
DOT 1 (-1600 2075);
DOT 1 (-1600 2025);
DOT 1 (-3850 2825);
DOT 1 (-3850 2775);
DOT 1 (-5050 1450);
DOT 1 (-5050 1500);
DOT 1 (-5050 1550);
DOT 1 (-3850 3925);
DOT 1 (-5050 3750);
DOT 1 (-5050 3800);
DOT 1 (-5050 3500);
DOT 1 (-5050 3650);
DOT 1 (-5050 3700);
DOT 1 (-5050 3600);
DOT 1 (-5050 3550);
DOT 1 (-5050 3250);
DOT 1 (-5050 3400);
DOT 1 (-5050 3450);
DOT 1 (-5050 3350);
DOT 1 (-5050 3100);
DOT 1 (-5050 3150);
DOT 1 (-5050 3200);
DOT 1 (-5050 3000);
DOT 1 (-5050 3050);
DOT 1 (-5050 2950);
DOT 1 (-5050 2900);
DOT 1 (-5050 2850);
DOT 1 (-5050 2750);
DOT 1 (-5050 2800);
DOT 1 (-5050 2700);
DOT 1 (-5050 2450);
DOT 1 (-5050 2650);
DOT 1 (-5050 2600);
DOT 1 (-5050 2500);
DOT 1 (-5050 2550);
DOT 1 (-5050 2200);
DOT 1 (-5050 2400);
DOT 1 (-5050 2350);
DOT 1 (-5050 2250);
DOT 1 (-5050 2300);
DOT 1 (-5050 1950);
DOT 1 (-5050 2150);
DOT 1 (-5050 2100);
DOT 1 (-5050 2050);
DOT 1 (-5050 2000);
DOT 1 (-5050 1700);
DOT 1 (-5050 1850);
DOT 1 (-5050 1900);
DOT 1 (-5050 1800);
DOT 1 (-5050 1750);
DOT 1 (-5050 1600);
DOT 1 (-5050 1650);
DOT 1 (-7325 3850);
DOT 1 (-7325 3800);
DOT 1 (-7325 3750);
DOT 1 (-7325 3700);
DOT 1 (-7325 3650);
DOT 1 (-7325 3600);
DOT 1 (-7325 3500);
DOT 1 (-7325 3450);
DOT 1 (-7325 3400);
DOT 1 (-7325 3350);
DOT 1 (-7325 3250);
DOT 1 (-7325 3300);
DOT 1 (-7325 3200);
DOT 1 (-7325 3100);
DOT 1 (-7325 3050);
DOT 1 (-7325 3000);
DOT 1 (-7325 2950);
DOT 1 (-7325 2900);
DOT 1 (-7325 2850);
DOT 1 (-7325 2800);
DOT 1 (-7325 2750);
DOT 1 (-7325 2700);
DOT 1 (-7325 2650);
DOT 1 (-7325 2550);
DOT 1 (-7325 2500);
DOT 1 (-7325 2350);
DOT 1 (-7325 2400);
DOT 1 (-7325 2300);
DOT 1 (-7325 2250);
DOT 1 (-7325 2200);
DOT 1 (-7325 2100);
DOT 1 (-7325 2150);
DOT 1 (-7325 2050);
DOT 1 (-7325 2000);
DOT 1 (-7325 1950);
DOT 1 (-7325 1900);
DOT 1 (-7325 1850);
DOT 1 (-7325 1800);
DOT 1 (-7325 1750);
DOT 1 (-7325 1700);
DOT 1 (-7325 1650);
DOT 1 (-7325 1600);
DOT 1 (-7325 1550);
DOT 1 (-7325 1450);
DOT 1 (-7325 1500);
DOT 1 (-7325 1350);
DOT 1 (-7325 1300);
DOT 1 (-3850 1225);
DOT 1 (-3850 1375);
DOT 1 (-3850 1275);
DOT 1 (-3850 1325);
DOT 1 (-3850 1425);
DOT 1 (-3850 1625);
DOT 1 (-3850 1675);
DOT 1 (-3850 1725);
DOT 1 (-3850 1775);
DOT 1 (-3850 1875);
DOT 1 (-3850 1825);
DOT 1 (-3850 2025);
DOT 1 (-3850 2125);
DOT 1 (-3850 2075);
DOT 1 (-3850 2275);
DOT 1 (-3850 2225);
DOT 1 (-3850 2175);
DOT 1 (-3850 2375);
DOT 1 (-3850 2475);
DOT 1 (-3850 2425);
DOT 1 (-3850 2625);
DOT 1 (-3850 2675);
DOT 1 (-3850 2725);
DOT 1 (-3850 2875);
DOT 1 (-3850 2925);
DOT 1 (-3850 3025);
DOT 1 (-3850 2975);
DOT 1 (-3850 3075);
DOT 1 (-3850 3175);
DOT 1 (-3850 3125);
DOT 1 (-3850 3275);
DOT 1 (-3850 3325);
DOT 1 (-3850 3425);
DOT 1 (-3850 3375);
DOT 1 (-3850 3475);
DOT 1 (-3850 3525);
DOT 1 (-3850 3575);
DOT 1 (-3850 3725);
DOT 1 (-3850 3775);
DOT 1 (-3850 3825);
DOT 1 (-3850 3975);
DOT 1 (-3850 4025);
DOT 1 (-1600 1875);
DOT 1 (-1600 2275);
DOT 1 (-1600 2325);
DOT 1 (-1600 2775);
DOT 1 (-1600 2825);
DOT 1 (-1600 2875);
DOT 1 (-1600 2925);
DOT 1 (-1600 3025);
DOT 1 (-1600 2975);
DOT 1 (-1600 3075);
DOT 1 (-1600 3425);
DOT 1 (-1600 3375);
DOT 1 (-1600 3475);
DOT 1 (-1600 3525);
DOT 1 (-1600 3575);
DOT 1 (-1600 3675);
DOT 1 (-1600 3625);
DOT 1 (-1600 3725);
DOT 1 (-1600 3775);
DOT 1 (-1600 3825);
DOT 1 (-1600 3925);
DOT 1 (-1600 3875);
DOT 1 (-1600 3975);
DOT 1 (-1600 4075);
DOT 1 (-3850 4075);
DOT 1 (-3850 4175);
DOT 1 (-3850 4125);
DOT 1 (-3850 4325);
DOT 1 (-3850 4275);
DOT 1 (-3850 4225);
DOT 1 (-3850 4375);
DOT 1 (-3850 4425);
DOT 1 (-3850 4475);
DOT 1 (-1600 4125);
DOT 1 (-1600 4225);
DOT 1 (-1600 4275);
DOT 1 (-1600 4325);
DOT 1 (-1600 4375);
DOT 1 (-1600 4425);
DOT 1 (-1600 4175);
DOT 1 (-1600 4475);
DOT 1 (-1600 4525);
DOT 1 (-1600 4575);
DOT 1 (-3850 4525);
DOT 1 (-3850 4575);
DOT 1 (-3850 925);
DOT 1 (-3850 975);
DOT 1 (-3850 1025);
DOT 1 (-3850 1075);
DOT 1 (-3850 1125);
DOT 1 (-3850 1925);
DOT 1 (-3850 2325);
DOT 1 (-3850 1975);
DOT 1 (-3850 1575);
DOT 1 (-3850 1175);
DOT 1 (-3850 1475);
DOT 1 (-1600 2725);
DOT 1 (-1600 2675);
DOT 1 (-1600 3175);
DOT 1 (-1600 2125);
DOT 1 (-1600 1825);
DOT 1 (-3850 2525);
DOT 1 (-1450 825);
DOT 1 (-1450 875);
DOT 1 (-1450 775);
DOT 1 (-1450 675);
DOT 1 (-5050 1350);
DOT 1 (-1450 625);
DOT 1 (-1450 575);
DOT 1 (-7325 3150);
DOT 1 (-1600 2475);
DOT 1 (-7325 2450);
DOT 1 (-3850 1525);
DOT 1 (-5050 3850);
DOT 1 (-1600 3125);
DOT 1 (-1600 3150);
DOT 1 (-1450 975);
DOT 1 (-1600 2425);
DOT 1 (-1450 925);
DOT 1 (-7325 3550);
DOT 1 (-1425 1625);
DOT 1 (-1425 1525);
DOT 1 (-1600 1775);
DOT 1 (-1600 1925);
DOT 1 (-3850 3225);
DOT 1 (-1450 1275);
DOT 1 (-1450 1325);
FORCENOTE
TP FAB4 ADD ATTRIBUTE GROUP=PWR_MCP_CAP 20170508
(-1150 850) 0;
DISPLAY LEFT (-1150 850);
DISPLAY 0.638298 (-1150 850);
PAINT RED (-1150 850);
FORCENOTE
ROOM=CPU1
(-7950 325) 0;
DISPLAY LEFT (-7950 325);
DISPLAY 1.723404 (-7950 325);
PAINT PURPLE (-7950 325);
FORCENOTE
BOM_COST=PROC_SOCKET
(-7950 200) 0;
DISPLAY LEFT (-7950 200);
DISPLAY 1.723404 (-7950 200);
PAINT PURPLE (-7950 200);
QUIT
